FILE_TYPE = MACRO_DRAWING;
SET COLOR_WIRE YELLOW;
SET COLOR_PROP ORANGE;
SET COLOR_DOT WHITE;
SET COLOR_ARC YELLOW;
SET COLOR_BODY GREEN;
SET COLOR_NOTE PURPLE;
SET PROP_DISPLAY VALUE;
SET PAGE_NUMBER P185;
FORCEADD OFFPAGE..4
R 2
(-5950 3200);
FORCEPROP 2 LAST $XR0 80 
J 0
(-6201 3200);
DISPLAY 0.638298 (-6201 3200);
PAINT MONO (-6201 3200);
FORCEPROP 2 LAST CDS_LIB standard
J 0
(-5950 3200);
DISPLAY INVISIBLE (-5950 3200);
FORCEPROP 1 LAST OFFPAGE TRUE
J 2
(-6275 3075);
DISPLAY 0.872340 (-6275 3075);
PAINT GREEN (-6275 3075);
DISPLAY INVISIBLE (-6275 3075);
FORCEPROP 1 LAST COMMENT_BODY TRUE
J 2
(-5925 3100);
DISPLAY 0.872340 (-5925 3100);
PAINT GREEN (-5925 3100);
DISPLAY INVISIBLE (-5925 3100);
FORCEPROP 2 LAST PATH I1
J 0
(-6225 3250);
DISPLAY 0.680851 (-6225 3250);
DISPLAY INVISIBLE (-6225 3250);
FORCEADD Q_RES..2
(-5125 7750);
FORCEPROP 1 LAST LOCATION PR151
J 0
(-5075 7875);
DISPLAY 0.489362 (-5075 7875);
PAINT SKYBLUE (-5075 7875);
FORCEPROP 0 LAST $SEC 1
J 0
(-5075 7900);
DISPLAY 0.680851 (-5075 7900);
PAINT MONO (-5075 7900);
DISPLAY INVISIBLE (-5075 7900);
FORCEPROP 0 LAST CDS_SEC 1
J 0
(-5075 7900);
DISPLAY 1.021277 (-5075 7900);
DISPLAY INVISIBLE (-5075 7900);
FORCEPROP 1 LASTPIN (-5125 7850) $PN 1
J 0
(-5120 7812);
DISPLAY 0.489362 (-5120 7812);
PAINT MONO (-5120 7812);
FORCEPROP 1 LASTPIN (-5125 7650) $PN 2
J 0
(-5120 7660);
DISPLAY 0.489362 (-5120 7660);
PAINT MONO (-5120 7660);
FORCEPROP 1 LAST MATERIAL EMPTY
J 0
(-5075 7675);
DISPLAY 0.489362 (-5075 7675);
PAINT RED (-5075 7675);
FORCEPROP 1 LAST WATTAGE 1/16W
J 0
(-5075 7725);
DISPLAY 0.489362 (-5075 7725);
PAINT SKYBLUE (-5075 7725);
FORCEPROP 1 LAST VALUE 1K
J 0
(-5075 7825);
DISPLAY 0.489362 (-5075 7825);
PAINT SKYBLUE (-5075 7825);
FORCEPROP 1 LAST TOLERANCE 1%
J 0
(-5075 7775);
DISPLAY 0.489362 (-5075 7775);
PAINT SKYBLUE (-5075 7775);
FORCEPROP 1 LAST PACK_TYPE 0402LF
J 0
(-5075 7625);
DISPLAY 0.489362 (-5075 7625);
PAINT SKYBLUE (-5075 7625);
FORCEPROP 2 LAST CDS_LIB pure_quanta
J 0
(-5125 7750);
DISPLAY INVISIBLE (-5125 7750);
FORCEPROP 1 LAST PATH I10
J 0
(-5075 7925);
DISPLAY 0.978723 (-5075 7925);
PAINT WHITE (-5075 7925);
DISPLAY INVISIBLE (-5075 7925);
FORCEPROP 1 LAST PART_NUMBER CS21002FB06
J 0
(-5075 7625);
DISPLAY 0.489362 (-5075 7625);
PAINT SKYBLUE (-5075 7625);
DISPLAY INVISIBLE (-5075 7625);
FORCEADD OFFPAGE..4
(450 4075);
FORCEPROP 2 LAST $XR0 216 
J 0
(636 4075);
DISPLAY 0.638298 (636 4075);
PAINT MONO (636 4075);
FORCEPROP 2 LAST CDS_LIB standard
J 0
(450 4075);
DISPLAY INVISIBLE (450 4075);
FORCEPROP 1 LAST OFFPAGE TRUE
J 0
(775 3950);
DISPLAY 0.872340 (775 3950);
PAINT GREEN (775 3950);
DISPLAY INVISIBLE (775 3950);
FORCEPROP 1 LAST COMMENT_BODY TRUE
J 0
(425 3975);
DISPLAY 0.872340 (425 3975);
PAINT GREEN (425 3975);
DISPLAY INVISIBLE (425 3975);
FORCEPROP 2 LAST PATH I100
J 0
(650 4125);
DISPLAY 0.680851 (650 4125);
DISPLAY INVISIBLE (650 4125);
FORCEADD OFFPAGE..2
(450 3875);
FORCEPROP 2 LAST $XR0 215 
J 0
(639 3875);
DISPLAY 0.638298 (639 3875);
PAINT MONO (639 3875);
FORCEPROP 2 LAST CDS_LIB standard
J 0
(450 3875);
DISPLAY INVISIBLE (450 3875);
FORCEPROP 1 LAST OFFPAGE TRUE
J 0
(775 3750);
DISPLAY 0.872340 (775 3750);
PAINT GREEN (775 3750);
DISPLAY INVISIBLE (775 3750);
FORCEPROP 1 LAST COMMENT_BODY TRUE
J 0
(405 3780);
DISPLAY 0.872340 (405 3780);
PAINT GREEN (405 3780);
DISPLAY INVISIBLE (405 3780);
FORCEPROP 2 LAST PATH I101
J 0
(650 3925);
DISPLAY 0.680851 (650 3925);
DISPLAY INVISIBLE (650 3925);
FORCEADD Q_RES..1
(400 4375);
FORCEPROP 1 LAST LOCATION PR437
J 0
(350 4425);
DISPLAY 0.489362 (350 4425);
PAINT SKYBLUE (350 4425);
FORCEPROP 0 LAST $SEC 1
J 0
(350 4450);
DISPLAY 0.680851 (350 4450);
PAINT MONO (350 4450);
DISPLAY INVISIBLE (350 4450);
FORCEPROP 0 LAST CDS_SEC 1
J 0
(350 4450);
DISPLAY 0.680851 (350 4450);
DISPLAY INVISIBLE (350 4450);
FORCEPROP 1 LASTPIN (300 4375) $PN 1
J 0
(312 4387);
DISPLAY 0.787234 (312 4387);
PAINT MONO (312 4387);
DISPLAY INVISIBLE (312 4387);
FORCEPROP 1 LASTPIN (500 4375) $PN 2
J 0
(462 4387);
DISPLAY 0.787234 (462 4387);
PAINT MONO (462 4387);
DISPLAY INVISIBLE (462 4387);
FORCEPROP 1 LAST PACK_TYPE 0402LF
J 0
(500 4325);
DISPLAY 0.489362 (500 4325);
PAINT SKYBLUE (500 4325);
FORCEPROP 1 LAST VALUE 0
J 2
(400 4325);
DISPLAY 0.489362 (400 4325);
PAINT SKYBLUE (400 4325);
FORCEPROP 1 LAST TOLERANCE 5%
J 0
(425 4325);
DISPLAY 0.489362 (425 4325);
PAINT SKYBLUE (425 4325);
FORCEPROP 1 LAST MATERIAL CHIP
J 0
(75 4325);
DISPLAY 0.489362 (75 4325);
PAINT SKYBLUE (75 4325);
FORCEPROP 1 LAST WATTAGE 1/16W
J 2
(325 4325);
DISPLAY 0.489362 (325 4325);
PAINT SKYBLUE (325 4325);
FORCEPROP 2 LAST CDS_LIB pure_quanta
J 0
(400 4375);
DISPLAY INVISIBLE (400 4375);
FORCEPROP 1 LAST PATH I102
J 0
(350 4525);
DISPLAY 0.978723 (350 4525);
PAINT WHITE (350 4525);
DISPLAY INVISIBLE (350 4525);
FORCEPROP 1 LAST PART_NUMBER CS00002JB13
J 0
(-275 4325);
DISPLAY 0.489362 (-275 4325);
PAINT SKYBLUE (-275 4325);
DISPLAY INVISIBLE (-275 4325);
FORCEADD Q_RES..1
(400 4675);
FORCEPROP 1 LAST LOCATION PR436
J 0
(350 4725);
DISPLAY 0.489362 (350 4725);
PAINT SKYBLUE (350 4725);
FORCEPROP 0 LAST $SEC 1
J 0
(350 4750);
DISPLAY 0.680851 (350 4750);
PAINT MONO (350 4750);
DISPLAY INVISIBLE (350 4750);
FORCEPROP 0 LAST CDS_SEC 1
J 0
(350 4750);
DISPLAY 1.021277 (350 4750);
DISPLAY INVISIBLE (350 4750);
FORCEPROP 1 LASTPIN (300 4675) $PN 1
J 0
(312 4687);
DISPLAY 0.489362 (312 4687);
PAINT MONO (312 4687);
FORCEPROP 1 LASTPIN (500 4675) $PN 2
J 0
(462 4687);
DISPLAY 0.489362 (462 4687);
PAINT MONO (462 4687);
FORCEPROP 1 LAST VALUE 0
J 2
(400 4625);
DISPLAY 0.489362 (400 4625);
PAINT SKYBLUE (400 4625);
FORCEPROP 1 LAST MATERIAL CHIP
J 0
(75 4625);
DISPLAY 0.489362 (75 4625);
PAINT SKYBLUE (75 4625);
FORCEPROP 1 LAST WATTAGE 1/16W
J 2
(325 4625);
DISPLAY 0.489362 (325 4625);
PAINT SKYBLUE (325 4625);
FORCEPROP 1 LAST PACK_TYPE 0402LF
J 0
(500 4625);
DISPLAY 0.489362 (500 4625);
PAINT SKYBLUE (500 4625);
FORCEPROP 1 LAST TOLERANCE 5%
J 0
(425 4625);
DISPLAY 0.489362 (425 4625);
PAINT SKYBLUE (425 4625);
FORCEPROP 2 LAST CDS_LIB pure_quanta
J 0
(400 4675);
DISPLAY INVISIBLE (400 4675);
FORCEPROP 1 LAST PATH I103
J 0
(350 4825);
DISPLAY 0.978723 (350 4825);
PAINT WHITE (350 4825);
DISPLAY INVISIBLE (350 4825);
FORCEPROP 1 LAST PART_NUMBER CS00002JB13
J 0
(-275 4625);
DISPLAY 0.489362 (-275 4625);
PAINT SKYBLUE (-275 4625);
DISPLAY INVISIBLE (-275 4625);
FORCEADD UNIVERSAL_GND..1
(725 4250);
FORCEPROP 3 LASTPIN (725 4300) SIG_NAME GND\g
J 0
(735 4310);
DISPLAY 0.659574 (735 4310);
PAINT MONO (735 4310);
DISPLAY INVISIBLE (735 4310);
FORCEPROP 2 LAST CDS_LIB pure_quanta_power
J 0
(725 4250);
DISPLAY INVISIBLE (725 4250);
FORCEPROP 1 LAST HDL_POWER GND
J 1
(750 4175);
DISPLAY 0.872340 (750 4175);
PAINT GREEN (750 4175);
DISPLAY INVISIBLE (750 4175);
FORCEPROP 1 LAST PATH I104
J 0
(800 4250);
DISPLAY 0.872340 (800 4250);
PAINT AQUA (800 4250);
DISPLAY INVISIBLE (800 4250);
FORCEADD UNIVERSAL_GND..1
(725 4550);
FORCEPROP 3 LASTPIN (725 4600) SIG_NAME GND\g
J 0
(735 4610);
DISPLAY 0.659574 (735 4610);
PAINT MONO (735 4610);
DISPLAY INVISIBLE (735 4610);
FORCEPROP 2 LAST CDS_LIB pure_quanta_power
J 0
(725 4550);
DISPLAY INVISIBLE (725 4550);
FORCEPROP 1 LAST HDL_POWER GND
J 1
(750 4475);
DISPLAY 0.872340 (750 4475);
PAINT GREEN (750 4475);
DISPLAY INVISIBLE (750 4475);
FORCEPROP 1 LAST PATH I105
J 0
(800 4550);
DISPLAY 0.872340 (800 4550);
PAINT AQUA (800 4550);
DISPLAY INVISIBLE (800 4550);
FORCEADD UNIVERSAL_GND..1
(725 4850);
FORCEPROP 3 LASTPIN (725 4900) SIG_NAME GND\g
J 0
(735 4910);
DISPLAY 0.659574 (735 4910);
PAINT MONO (735 4910);
DISPLAY INVISIBLE (735 4910);
FORCEPROP 2 LAST CDS_LIB pure_quanta_power
J 0
(725 4850);
DISPLAY INVISIBLE (725 4850);
FORCEPROP 1 LAST HDL_POWER GND
J 1
(750 4775);
DISPLAY 0.872340 (750 4775);
PAINT GREEN (750 4775);
DISPLAY INVISIBLE (750 4775);
FORCEPROP 1 LAST PATH I106
J 0
(800 4850);
DISPLAY 0.872340 (800 4850);
PAINT AQUA (800 4850);
DISPLAY INVISIBLE (800 4850);
FORCEADD Q_RES..1
(400 4975);
FORCEPROP 1 LAST LOCATION PR530
J 0
(350 5025);
DISPLAY 0.489362 (350 5025);
PAINT SKYBLUE (350 5025);
FORCEPROP 0 LAST $SEC 1
J 0
(350 5050);
DISPLAY 0.680851 (350 5050);
PAINT MONO (350 5050);
DISPLAY INVISIBLE (350 5050);
FORCEPROP 0 LAST CDS_SEC 1
J 0
(350 5050);
DISPLAY 1.021277 (350 5050);
DISPLAY INVISIBLE (350 5050);
FORCEPROP 1 LASTPIN (300 4975) $PN 1
J 0
(312 4987);
DISPLAY 0.489362 (312 4987);
PAINT MONO (312 4987);
FORCEPROP 1 LASTPIN (500 4975) $PN 2
J 0
(462 4987);
DISPLAY 0.489362 (462 4987);
PAINT MONO (462 4987);
FORCEPROP 1 LAST TOLERANCE 5%
J 0
(425 4925);
DISPLAY 0.489362 (425 4925);
PAINT SKYBLUE (425 4925);
FORCEPROP 1 LAST MATERIAL CHIP
J 0
(75 4925);
DISPLAY 0.489362 (75 4925);
PAINT SKYBLUE (75 4925);
FORCEPROP 1 LAST WATTAGE 1/16W
J 2
(325 4925);
DISPLAY 0.489362 (325 4925);
PAINT SKYBLUE (325 4925);
FORCEPROP 1 LAST VALUE 0
J 2
(400 4925);
DISPLAY 0.489362 (400 4925);
PAINT SKYBLUE (400 4925);
FORCEPROP 1 LAST PACK_TYPE 0402LF
J 0
(500 4925);
DISPLAY 0.489362 (500 4925);
PAINT SKYBLUE (500 4925);
FORCEPROP 2 LAST CDS_LIB pure_quanta
J 0
(400 4975);
DISPLAY INVISIBLE (400 4975);
FORCEPROP 1 LAST PATH I107
J 0
(350 5125);
DISPLAY 0.978723 (350 5125);
PAINT WHITE (350 5125);
DISPLAY INVISIBLE (350 5125);
FORCEPROP 1 LAST PART_NUMBER CS00002JB13
J 0
(-275 4925);
DISPLAY 0.489362 (-275 4925);
PAINT SKYBLUE (-275 4925);
DISPLAY INVISIBLE (-275 4925);
FORCEADD OFFPAGE..4
(425 5275);
FORCEPROP 2 LAST $XR0 213 
J 0
(611 5275);
DISPLAY 0.638298 (611 5275);
PAINT MONO (611 5275);
FORCEPROP 2 LAST CDS_LIB standard
J 0
(425 5275);
DISPLAY INVISIBLE (425 5275);
FORCEPROP 1 LAST OFFPAGE TRUE
J 0
(750 5150);
DISPLAY 0.872340 (750 5150);
PAINT GREEN (750 5150);
DISPLAY INVISIBLE (750 5150);
FORCEPROP 1 LAST COMMENT_BODY TRUE
J 0
(400 5175);
DISPLAY 0.872340 (400 5175);
PAINT GREEN (400 5175);
DISPLAY INVISIBLE (400 5175);
FORCEPROP 2 LAST PATH I108
J 0
(625 5325);
DISPLAY 0.680851 (625 5325);
DISPLAY INVISIBLE (625 5325);
FORCEADD OFFPAGE..2
(425 5375);
FORCEPROP 2 LAST $XR0 213 
J 0
(614 5375);
DISPLAY 0.638298 (614 5375);
PAINT MONO (614 5375);
FORCEPROP 2 LAST CDS_LIB standard
J 0
(425 5375);
DISPLAY INVISIBLE (425 5375);
FORCEPROP 1 LAST OFFPAGE TRUE
J 0
(750 5250);
DISPLAY 0.872340 (750 5250);
PAINT GREEN (750 5250);
DISPLAY INVISIBLE (750 5250);
FORCEPROP 1 LAST COMMENT_BODY TRUE
J 0
(380 5280);
DISPLAY 0.872340 (380 5280);
PAINT GREEN (380 5280);
DISPLAY INVISIBLE (380 5280);
FORCEPROP 2 LAST PATH I109
J 0
(625 5425);
DISPLAY 0.680851 (625 5425);
DISPLAY INVISIBLE (625 5425);
FORCEADD VCC_CORE..1
(-5125 8050);
FORCEPROP 3 LASTPIN (-5125 8000) SIG_NAME PVDD18_S5_P1\g
J 0
(-5115 8010);
DISPLAY 0.659574 (-5115 8010);
PAINT MONO (-5115 8010);
DISPLAY INVISIBLE (-5115 8010);
FORCEPROP 1 LAST HDL_POWER PVDD18_S5_P1
J 1
(-5125 8100);
DISPLAY 0.489362 (-5125 8100);
PAINT GREEN (-5125 8100);
FORCEPROP 2 LAST CDS_LIB pure_quanta_power
J 0
(-5125 8050);
DISPLAY INVISIBLE (-5125 8050);
FORCEPROP 1 LAST PATH I11
J 0
(-5075 8075);
DISPLAY 0.872340 (-5075 8075);
PAINT AQUA (-5075 8075);
DISPLAY INVISIBLE (-5075 8075);
FORCEADD OFFPAGE..2
(425 5675);
FORCEPROP 2 LAST $XR0 213 
J 0
(614 5675);
DISPLAY 0.638298 (614 5675);
PAINT MONO (614 5675);
FORCEPROP 2 LAST CDS_LIB standard
J 0
(425 5675);
DISPLAY INVISIBLE (425 5675);
FORCEPROP 1 LAST OFFPAGE TRUE
J 0
(750 5550);
DISPLAY 0.872340 (750 5550);
PAINT GREEN (750 5550);
DISPLAY INVISIBLE (750 5550);
FORCEPROP 1 LAST COMMENT_BODY TRUE
J 0
(380 5580);
DISPLAY 0.872340 (380 5580);
PAINT GREEN (380 5580);
DISPLAY INVISIBLE (380 5580);
FORCEPROP 2 LAST PATH I110
J 0
(625 5725);
DISPLAY 0.680851 (625 5725);
DISPLAY INVISIBLE (625 5725);
FORCEADD OFFPAGE..4
(425 5575);
FORCEPROP 2 LAST $XR0 213 
J 0
(611 5575);
DISPLAY 0.638298 (611 5575);
PAINT MONO (611 5575);
FORCEPROP 2 LAST CDS_LIB standard
J 0
(425 5575);
DISPLAY INVISIBLE (425 5575);
FORCEPROP 1 LAST OFFPAGE TRUE
J 0
(750 5450);
DISPLAY 0.872340 (750 5450);
PAINT GREEN (750 5450);
DISPLAY INVISIBLE (750 5450);
FORCEPROP 1 LAST COMMENT_BODY TRUE
J 0
(400 5475);
DISPLAY 0.872340 (400 5475);
PAINT GREEN (400 5475);
DISPLAY INVISIBLE (400 5475);
FORCEPROP 2 LAST PATH I111
J 0
(625 5625);
DISPLAY 0.680851 (625 5625);
DISPLAY INVISIBLE (625 5625);
FORCEADD OFFPAGE..4
(425 5875);
FORCEPROP 2 LAST $XR0 212 
J 0
(611 5875);
DISPLAY 0.638298 (611 5875);
PAINT MONO (611 5875);
FORCEPROP 2 LAST CDS_LIB standard
J 0
(425 5875);
DISPLAY INVISIBLE (425 5875);
FORCEPROP 1 LAST OFFPAGE TRUE
J 0
(750 5750);
DISPLAY 0.872340 (750 5750);
PAINT GREEN (750 5750);
DISPLAY INVISIBLE (750 5750);
FORCEPROP 1 LAST COMMENT_BODY TRUE
J 0
(400 5775);
DISPLAY 0.872340 (400 5775);
PAINT GREEN (400 5775);
DISPLAY INVISIBLE (400 5775);
FORCEPROP 2 LAST PATH I112
J 0
(625 5925);
DISPLAY 0.680851 (625 5925);
DISPLAY INVISIBLE (625 5925);
FORCEADD UNIVERSAL_GND..1
(-25 7200);
FORCEPROP 3 LASTPIN (-25 7250) SIG_NAME GND\g
J 0
(-15 7260);
DISPLAY 0.659574 (-15 7260);
PAINT MONO (-15 7260);
DISPLAY INVISIBLE (-15 7260);
FORCEPROP 2 LAST CDS_LIB pure_quanta_power
J 0
(-25 7200);
DISPLAY INVISIBLE (-25 7200);
FORCEPROP 1 LAST HDL_POWER GND
J 1
(0 7125);
DISPLAY 0.872340 (0 7125);
PAINT GREEN (0 7125);
DISPLAY INVISIBLE (0 7125);
FORCEPROP 1 LAST PATH I113
J 0
(50 7200);
DISPLAY 0.872340 (50 7200);
PAINT AQUA (50 7200);
DISPLAY INVISIBLE (50 7200);
FORCEADD Q_CAP..1
(-25 7425);
FORCEPROP 1 LAST LOCATION PC11
J 0
(25 7525);
DISPLAY 0.489362 (25 7525);
PAINT SKYBLUE (25 7525);
FORCEPROP 0 LAST $SEC 1
J 0
(25 7550);
DISPLAY 0.680851 (25 7550);
PAINT MONO (25 7550);
DISPLAY INVISIBLE (25 7550);
FORCEPROP 0 LAST CDS_SEC 1
J 0
(25 7550);
DISPLAY 1.021277 (25 7550);
DISPLAY INVISIBLE (25 7550);
FORCEPROP 1 LASTPIN (-25 7525) $PN 1
J 0
(-15 7505);
DISPLAY 0.489362 (-15 7505);
PAINT MONO (-15 7505);
FORCEPROP 1 LASTPIN (-25 7325) $PN 2
J 0
(-15 7305);
DISPLAY 0.489362 (-15 7305);
PAINT MONO (-15 7305);
FORCEPROP 1 LAST PACK_TYPE 0402
J 0
(25 7225);
DISPLAY 0.489362 (25 7225);
PAINT SKYBLUE (25 7225);
FORCEPROP 1 LAST MATERIAL X7R
J 0
(25 7325);
DISPLAY 0.489362 (25 7325);
PAINT SKYBLUE (25 7325);
FORCEPROP 1 LAST TOLERANCE 10%
J 0
(25 7375);
DISPLAY 0.489362 (25 7375);
PAINT SKYBLUE (25 7375);
FORCEPROP 1 LAST VALUE 0.1UF
J 0
(25 7475);
DISPLAY 0.489362 (25 7475);
PAINT SKYBLUE (25 7475);
FORCEPROP 1 LAST VOLTAGE 25V
J 0
(25 7425);
DISPLAY 0.489362 (25 7425);
PAINT SKYBLUE (25 7425);
FORCEPROP 2 LAST CDS_LIB pure_quanta
J 0
(-25 7425);
DISPLAY INVISIBLE (-25 7425);
FORCEPROP 1 LAST PATH I114
J 0
(25 7575);
DISPLAY 0.978723 (25 7575);
PAINT WHITE (25 7575);
DISPLAY INVISIBLE (25 7575);
FORCEPROP 1 LAST PART_NUMBER CH4104K1B00
J 0
(25 7275);
DISPLAY 0.489362 (25 7275);
PAINT SKYBLUE (25 7275);
DISPLAY INVISIBLE (25 7275);
FORCEADD UNIVERSAL_GND..1
(-25 7650);
FORCEPROP 3 LASTPIN (-25 7700) SIG_NAME GND\g
J 0
(-15 7710);
DISPLAY 0.659574 (-15 7710);
PAINT MONO (-15 7710);
DISPLAY INVISIBLE (-15 7710);
FORCEPROP 2 LAST CDS_LIB pure_quanta_power
J 0
(-25 7650);
DISPLAY INVISIBLE (-25 7650);
FORCEPROP 1 LAST HDL_POWER GND
J 1
(0 7575);
DISPLAY 0.872340 (0 7575);
PAINT GREEN (0 7575);
DISPLAY INVISIBLE (0 7575);
FORCEPROP 1 LAST PATH I115
J 0
(50 7650);
DISPLAY 0.872340 (50 7650);
PAINT AQUA (50 7650);
DISPLAY INVISIBLE (50 7650);
FORCEADD Q_CAP..1
(-25 7900);
FORCEPROP 1 LAST LOCATION PC10
J 0
(25 8000);
DISPLAY 0.489362 (25 8000);
PAINT SKYBLUE (25 8000);
FORCEPROP 0 LAST $SEC 1
J 0
(25 8025);
DISPLAY 0.680851 (25 8025);
PAINT MONO (25 8025);
DISPLAY INVISIBLE (25 8025);
FORCEPROP 0 LAST CDS_SEC 1
J 0
(25 8025);
DISPLAY 1.021277 (25 8025);
DISPLAY INVISIBLE (25 8025);
FORCEPROP 1 LASTPIN (-25 8000) $PN 1
J 0
(-15 7980);
DISPLAY 0.489362 (-15 7980);
PAINT MONO (-15 7980);
FORCEPROP 1 LASTPIN (-25 7800) $PN 2
J 0
(-15 7780);
DISPLAY 0.489362 (-15 7780);
PAINT MONO (-15 7780);
FORCEPROP 1 LAST MATERIAL X7R
J 0
(25 7800);
DISPLAY 0.489362 (25 7800);
PAINT SKYBLUE (25 7800);
FORCEPROP 1 LAST TOLERANCE 10%
J 0
(25 7850);
DISPLAY 0.489362 (25 7850);
PAINT SKYBLUE (25 7850);
FORCEPROP 1 LAST VOLTAGE 25V
J 0
(25 7900);
DISPLAY 0.489362 (25 7900);
PAINT SKYBLUE (25 7900);
FORCEPROP 1 LAST PACK_TYPE 0402
J 0
(25 7700);
DISPLAY 0.489362 (25 7700);
PAINT SKYBLUE (25 7700);
FORCEPROP 1 LAST VALUE 0.1UF
J 0
(25 7950);
DISPLAY 0.489362 (25 7950);
PAINT SKYBLUE (25 7950);
FORCEPROP 2 LAST CDS_LIB pure_quanta
J 0
(-25 7900);
DISPLAY INVISIBLE (-25 7900);
FORCEPROP 1 LAST PATH I116
J 0
(25 8050);
DISPLAY 0.978723 (25 8050);
PAINT WHITE (25 8050);
DISPLAY INVISIBLE (25 8050);
FORCEPROP 1 LAST PART_NUMBER CH4104K1B00
J 0
(25 7750);
DISPLAY 0.489362 (25 7750);
PAINT SKYBLUE (25 7750);
DISPLAY INVISIBLE (25 7750);
FORCEADD OFFPAGE..2
(425 5975);
FORCEPROP 2 LAST $XR0 212 
J 0
(614 5975);
DISPLAY 0.638298 (614 5975);
PAINT MONO (614 5975);
FORCEPROP 2 LAST CDS_LIB standard
J 0
(425 5975);
DISPLAY INVISIBLE (425 5975);
FORCEPROP 1 LAST OFFPAGE TRUE
J 0
(750 5850);
DISPLAY 0.872340 (750 5850);
PAINT GREEN (750 5850);
DISPLAY INVISIBLE (750 5850);
FORCEPROP 1 LAST COMMENT_BODY TRUE
J 0
(380 5880);
DISPLAY 0.872340 (380 5880);
PAINT GREEN (380 5880);
DISPLAY INVISIBLE (380 5880);
FORCEPROP 2 LAST PATH I117
J 0
(625 6025);
DISPLAY 0.680851 (625 6025);
DISPLAY INVISIBLE (625 6025);
FORCEADD OFFPAGE..2
(450 6275);
FORCEPROP 2 LAST $XR0 212 
J 0
(639 6275);
DISPLAY 0.638298 (639 6275);
PAINT MONO (639 6275);
FORCEPROP 2 LAST CDS_LIB standard
J 0
(450 6275);
DISPLAY INVISIBLE (450 6275);
FORCEPROP 1 LAST OFFPAGE TRUE
J 0
(775 6150);
DISPLAY 0.872340 (775 6150);
PAINT GREEN (775 6150);
DISPLAY INVISIBLE (775 6150);
FORCEPROP 1 LAST COMMENT_BODY TRUE
J 0
(405 6180);
DISPLAY 0.872340 (405 6180);
PAINT GREEN (405 6180);
DISPLAY INVISIBLE (405 6180);
FORCEPROP 2 LAST PATH I118
J 0
(650 6325);
DISPLAY 0.680851 (650 6325);
DISPLAY INVISIBLE (650 6325);
FORCEADD OFFPAGE..4
(450 6175);
FORCEPROP 2 LAST $XR0 212 
J 0
(636 6175);
DISPLAY 0.638298 (636 6175);
PAINT MONO (636 6175);
FORCEPROP 2 LAST CDS_LIB standard
J 0
(450 6175);
DISPLAY INVISIBLE (450 6175);
FORCEPROP 1 LAST OFFPAGE TRUE
J 0
(775 6050);
DISPLAY 0.872340 (775 6050);
PAINT GREEN (775 6050);
DISPLAY INVISIBLE (775 6050);
FORCEPROP 1 LAST COMMENT_BODY TRUE
J 0
(425 6075);
DISPLAY 0.872340 (425 6075);
PAINT GREEN (425 6075);
DISPLAY INVISIBLE (425 6075);
FORCEPROP 2 LAST PATH I119
J 0
(650 6225);
DISPLAY 0.680851 (650 6225);
DISPLAY INVISIBLE (650 6225);
FORCEADD UNIVERSAL_GND..1
(-4850 2725);
FORCEPROP 3 LASTPIN (-4850 2775) SIG_NAME GND\g
J 0
(-4840 2785);
DISPLAY 0.659574 (-4840 2785);
PAINT MONO (-4840 2785);
DISPLAY INVISIBLE (-4840 2785);
FORCEPROP 2 LAST CDS_LIB pure_quanta_power
J 0
(-4850 2725);
DISPLAY INVISIBLE (-4850 2725);
FORCEPROP 1 LAST HDL_POWER GND
J 1
(-4825 2650);
DISPLAY 0.872340 (-4825 2650);
PAINT GREEN (-4825 2650);
DISPLAY INVISIBLE (-4825 2650);
FORCEPROP 1 LAST PATH I12
J 0
(-4775 2725);
DISPLAY 0.872340 (-4775 2725);
PAINT AQUA (-4775 2725);
DISPLAY INVISIBLE (-4775 2725);
FORCEADD OFFPAGE..4
(450 6475);
FORCEPROP 2 LAST $XR0 211 
J 0
(636 6475);
DISPLAY 0.638298 (636 6475);
PAINT MONO (636 6475);
FORCEPROP 2 LAST CDS_LIB standard
J 0
(450 6475);
DISPLAY INVISIBLE (450 6475);
FORCEPROP 1 LAST OFFPAGE TRUE
J 0
(775 6350);
DISPLAY 0.872340 (775 6350);
PAINT GREEN (775 6350);
DISPLAY INVISIBLE (775 6350);
FORCEPROP 1 LAST COMMENT_BODY TRUE
J 0
(425 6375);
DISPLAY 0.872340 (425 6375);
PAINT GREEN (425 6375);
DISPLAY INVISIBLE (425 6375);
FORCEPROP 2 LAST PATH I120
J 0
(650 6525);
DISPLAY 0.680851 (650 6525);
DISPLAY INVISIBLE (650 6525);
FORCEADD OFFPAGE..2
(450 6575);
FORCEPROP 2 LAST $XR0 211 
J 0
(639 6575);
DISPLAY 0.638298 (639 6575);
PAINT MONO (639 6575);
FORCEPROP 2 LAST CDS_LIB standard
J 0
(450 6575);
DISPLAY INVISIBLE (450 6575);
FORCEPROP 1 LAST OFFPAGE TRUE
J 0
(775 6450);
DISPLAY 0.872340 (775 6450);
PAINT GREEN (775 6450);
DISPLAY INVISIBLE (775 6450);
FORCEPROP 1 LAST COMMENT_BODY TRUE
J 0
(405 6480);
DISPLAY 0.872340 (405 6480);
PAINT GREEN (405 6480);
DISPLAY INVISIBLE (405 6480);
FORCEPROP 2 LAST PATH I121
J 0
(650 6625);
DISPLAY 0.680851 (650 6625);
DISPLAY INVISIBLE (650 6625);
FORCEADD OFFPAGE..4
(425 6775);
FORCEPROP 2 LAST $XR0 211 
J 0
(611 6775);
DISPLAY 0.638298 (611 6775);
PAINT MONO (611 6775);
FORCEPROP 2 LAST CDS_LIB standard
J 0
(425 6775);
DISPLAY INVISIBLE (425 6775);
FORCEPROP 1 LAST OFFPAGE TRUE
J 0
(750 6650);
DISPLAY 0.872340 (750 6650);
PAINT GREEN (750 6650);
DISPLAY INVISIBLE (750 6650);
FORCEPROP 1 LAST COMMENT_BODY TRUE
J 0
(400 6675);
DISPLAY 0.872340 (400 6675);
PAINT GREEN (400 6675);
DISPLAY INVISIBLE (400 6675);
FORCEPROP 2 LAST PATH I122
J 0
(625 6825);
DISPLAY 0.680851 (625 6825);
DISPLAY INVISIBLE (625 6825);
FORCEADD OFFPAGE..2
(425 6875);
FORCEPROP 2 LAST $XR0 211 
J 0
(614 6875);
DISPLAY 0.638298 (614 6875);
PAINT MONO (614 6875);
FORCEPROP 2 LAST CDS_LIB standard
J 0
(425 6875);
DISPLAY INVISIBLE (425 6875);
FORCEPROP 1 LAST OFFPAGE TRUE
J 0
(750 6750);
DISPLAY 0.872340 (750 6750);
PAINT GREEN (750 6750);
DISPLAY INVISIBLE (750 6750);
FORCEPROP 1 LAST COMMENT_BODY TRUE
J 0
(380 6780);
DISPLAY 0.872340 (380 6780);
PAINT GREEN (380 6780);
DISPLAY INVISIBLE (380 6780);
FORCEPROP 2 LAST PATH I123
J 0
(625 6925);
DISPLAY 0.680851 (625 6925);
DISPLAY INVISIBLE (625 6925);
FORCEADD UNIVERSAL_GND..1
(300 7200);
FORCEPROP 3 LASTPIN (300 7250) SIG_NAME GND\g
J 0
(310 7260);
DISPLAY 0.659574 (310 7260);
PAINT MONO (310 7260);
DISPLAY INVISIBLE (310 7260);
FORCEPROP 2 LAST CDS_LIB pure_quanta_power
J 0
(300 7200);
DISPLAY INVISIBLE (300 7200);
FORCEPROP 1 LAST HDL_POWER GND
J 1
(325 7125);
DISPLAY 0.872340 (325 7125);
PAINT GREEN (325 7125);
DISPLAY INVISIBLE (325 7125);
FORCEPROP 1 LAST PATH I124
J 0
(375 7200);
DISPLAY 0.872340 (375 7200);
PAINT AQUA (375 7200);
DISPLAY INVISIBLE (375 7200);
FORCEADD Q_CAP..1
(300 7425);
FORCEPROP 1 LAST LOCATION PC251
J 0
(350 7525);
DISPLAY 0.489362 (350 7525);
PAINT SKYBLUE (350 7525);
FORCEPROP 0 LAST $SEC 1
J 0
(350 7550);
DISPLAY 0.680851 (350 7550);
PAINT MONO (350 7550);
DISPLAY INVISIBLE (350 7550);
FORCEPROP 0 LAST CDS_SEC 1
J 0
(350 7550);
DISPLAY 1.021277 (350 7550);
DISPLAY INVISIBLE (350 7550);
FORCEPROP 1 LASTPIN (300 7525) $PN 1
J 0
(310 7505);
DISPLAY 0.489362 (310 7505);
PAINT MONO (310 7505);
FORCEPROP 1 LASTPIN (300 7325) $PN 2
J 0
(310 7305);
DISPLAY 0.489362 (310 7305);
PAINT MONO (310 7305);
FORCEPROP 1 LAST PACK_TYPE C0402
J 0
(350 7225);
DISPLAY 0.489362 (350 7225);
PAINT SKYBLUE (350 7225);
FORCEPROP 1 LAST VOLTAGE 6.3V
J 0
(350 7425);
DISPLAY 0.489362 (350 7425);
PAINT SKYBLUE (350 7425);
FORCEPROP 1 LAST VALUE 10UF
J 0
(350 7475);
DISPLAY 0.489362 (350 7475);
PAINT SKYBLUE (350 7475);
FORCEPROP 1 LAST TOLERANCE 20%
J 0
(350 7375);
DISPLAY 0.489362 (350 7375);
PAINT SKYBLUE (350 7375);
FORCEPROP 1 LAST MATERIAL X6S
J 0
(350 7325);
DISPLAY 0.489362 (350 7325);
PAINT SKYBLUE (350 7325);
FORCEPROP 2 LAST CDS_LIB pure_quanta
J 0
(300 7425);
DISPLAY INVISIBLE (300 7425);
FORCEPROP 1 LAST PATH I125
J 0
(350 7575);
DISPLAY 0.978723 (350 7575);
PAINT WHITE (350 7575);
DISPLAY INVISIBLE (350 7575);
FORCEPROP 1 LAST PART_NUMBER CH6101MEB03
J 0
(350 7275);
DISPLAY 0.489362 (350 7275);
PAINT SKYBLUE (350 7275);
DISPLAY INVISIBLE (350 7275);
FORCEADD UNIVERSAL_GND..1
(325 7650);
FORCEPROP 3 LASTPIN (325 7700) SIG_NAME GND\g
J 0
(335 7710);
DISPLAY 0.659574 (335 7710);
PAINT MONO (335 7710);
DISPLAY INVISIBLE (335 7710);
FORCEPROP 2 LAST CDS_LIB pure_quanta_power
J 0
(325 7650);
DISPLAY INVISIBLE (325 7650);
FORCEPROP 1 LAST HDL_POWER GND
J 1
(350 7575);
DISPLAY 0.872340 (350 7575);
PAINT GREEN (350 7575);
DISPLAY INVISIBLE (350 7575);
FORCEPROP 1 LAST PATH I126
J 0
(400 7650);
DISPLAY 0.872340 (400 7650);
PAINT AQUA (400 7650);
DISPLAY INVISIBLE (400 7650);
FORCEADD Q_CAP..1
(325 7900);
FORCEPROP 1 LAST LOCATION PC252
J 0
(375 8000);
DISPLAY 0.489362 (375 8000);
PAINT SKYBLUE (375 8000);
FORCEPROP 0 LAST $SEC 1
J 0
(375 8025);
DISPLAY 0.680851 (375 8025);
PAINT MONO (375 8025);
DISPLAY INVISIBLE (375 8025);
FORCEPROP 0 LAST CDS_SEC 1
J 0
(375 8025);
DISPLAY 1.021277 (375 8025);
DISPLAY INVISIBLE (375 8025);
FORCEPROP 1 LASTPIN (325 8000) $PN 1
J 0
(335 7980);
DISPLAY 0.489362 (335 7980);
PAINT MONO (335 7980);
FORCEPROP 1 LASTPIN (325 7800) $PN 2
J 0
(335 7780);
DISPLAY 0.489362 (335 7780);
PAINT MONO (335 7780);
FORCEPROP 1 LAST TOLERANCE 10%
J 0
(375 7850);
DISPLAY 0.489362 (375 7850);
PAINT SKYBLUE (375 7850);
FORCEPROP 1 LAST VALUE 1UF
J 0
(375 7950);
DISPLAY 0.489362 (375 7950);
PAINT SKYBLUE (375 7950);
FORCEPROP 1 LAST PACK_TYPE C0402
J 0
(375 7700);
DISPLAY 0.489362 (375 7700);
PAINT SKYBLUE (375 7700);
FORCEPROP 1 LAST MATERIAL X6S
J 0
(375 7800);
DISPLAY 0.489362 (375 7800);
PAINT SKYBLUE (375 7800);
FORCEPROP 1 LAST VOLTAGE 16V
J 0
(375 7900);
DISPLAY 0.489362 (375 7900);
PAINT SKYBLUE (375 7900);
FORCEPROP 2 LAST CDS_LIB pure_quanta
J 0
(325 7900);
DISPLAY INVISIBLE (325 7900);
FORCEPROP 1 LAST PATH I127
J 0
(375 8050);
DISPLAY 0.978723 (375 8050);
PAINT WHITE (375 8050);
DISPLAY INVISIBLE (375 8050);
FORCEPROP 1 LAST PART_NUMBER CH5103KEB01
J 0
(375 7750);
DISPLAY 0.489362 (375 7750);
PAINT SKYBLUE (375 7750);
DISPLAY INVISIBLE (375 7750);
FORCEADD OFFPAGE..5
R 2
(750 7575);
FORCEPROP 2 LAST $XR0 211 
J 0
(939 7575);
DISPLAY 0.638298 (939 7575);
PAINT MONO (939 7575);
FORCEPROP 2 LAST $XR1 212 
J 0
(1059 7575);
DISPLAY 0.638298 (1059 7575);
PAINT MONO (1059 7575);
FORCEPROP 2 LAST $XR2 213 
J 0
(1179 7575);
DISPLAY 0.638298 (1179 7575);
PAINT MONO (1179 7575);
FORCEPROP 2 LAST $XR3 215 
J 0
(1299 7575);
DISPLAY 0.638298 (1299 7575);
PAINT MONO (1299 7575);
FORCEPROP 2 LAST $XR4 216 
J 0
(1419 7575);
DISPLAY 0.638298 (1419 7575);
PAINT MONO (1419 7575);
FORCEPROP 2 LAST CDS_LIB standard
J 2
(750 7575);
DISPLAY INVISIBLE (750 7575);
FORCEPROP 1 LAST OFFPAGE TRUE
J 2
(425 7450);
DISPLAY 0.872340 (425 7450);
PAINT GREEN (425 7450);
DISPLAY INVISIBLE (425 7450);
FORCEPROP 1 LAST COMMENT_BODY TRUE
J 2
(650 7500);
DISPLAY 0.872340 (650 7500);
PAINT GREEN (650 7500);
DISPLAY INVISIBLE (650 7500);
FORCEPROP 2 LAST PATH I128
J 0
(1425 7625);
DISPLAY 0.680851 (1425 7625);
DISPLAY INVISIBLE (1425 7625);
FORCEADD Q_RES..1
(750 8050);
FORCEPROP 1 LAST LOCATION PR183
J 0
(700 8100);
DISPLAY 0.489362 (700 8100);
PAINT SKYBLUE (700 8100);
FORCEPROP 0 LAST $SEC 1
J 0
(700 8150);
DISPLAY 0.680851 (700 8150);
PAINT MONO (700 8150);
DISPLAY INVISIBLE (700 8150);
FORCEPROP 0 LAST CDS_SEC 1
J 0
(700 8150);
DISPLAY 1.021277 (700 8150);
DISPLAY INVISIBLE (700 8150);
FORCEPROP 1 LASTPIN (650 8050) $PN 1
J 0
(662 8062);
DISPLAY 0.489362 (662 8062);
PAINT MONO (662 8062);
FORCEPROP 1 LASTPIN (850 8050) $PN 2
J 0
(812 8062);
DISPLAY 0.489362 (812 8062);
PAINT MONO (812 8062);
FORCEPROP 1 LAST PACK_TYPE 0402LF
J 0
(575 7975);
DISPLAY 0.489362 (575 7975);
PAINT SKYBLUE (575 7975);
FORCEPROP 1 LAST VALUE 1
J 2
(600 8075);
DISPLAY 0.489362 (600 8075);
PAINT SKYBLUE (600 8075);
FORCEPROP 1 LAST TOLERANCE 1%
J 0
(875 8075);
DISPLAY 0.489362 (875 8075);
PAINT SKYBLUE (875 8075);
FORCEPROP 1 LAST MATERIAL CHIP
J 0
(875 8000);
DISPLAY 0.489362 (875 8000);
PAINT SKYBLUE (875 8000);
FORCEPROP 1 LAST WATTAGE 1/16W
J 0
(875 7975);
DISPLAY 0.489362 (875 7975);
PAINT SKYBLUE (875 7975);
FORCEPROP 2 LAST CDS_LIB pure_quanta
J 0
(750 8050);
DISPLAY INVISIBLE (750 8050);
FORCEPROP 1 LAST PATH I129
J 0
(700 8200);
DISPLAY 0.978723 (700 8200);
PAINT WHITE (700 8200);
DISPLAY INVISIBLE (700 8200);
FORCEPROP 1 LAST PART_NUMBER CS-1002FB04
J 0
(575 8000);
DISPLAY 0.489362 (575 8000);
PAINT SKYBLUE (575 8000);
DISPLAY INVISIBLE (575 8000);
FORCEADD Q_CAP..1
(-4850 2950);
FORCEPROP 1 LAST LOCATION C242
J 0
(-4800 3050);
DISPLAY 0.489362 (-4800 3050);
PAINT SKYBLUE (-4800 3050);
FORCEPROP 0 LAST $SEC 1
J 0
(-4800 3075);
DISPLAY 0.680851 (-4800 3075);
PAINT MONO (-4800 3075);
DISPLAY INVISIBLE (-4800 3075);
FORCEPROP 0 LAST CDS_SEC 1
J 0
(-4800 3075);
DISPLAY 1.021277 (-4800 3075);
DISPLAY INVISIBLE (-4800 3075);
FORCEPROP 1 LASTPIN (-4850 3050) $PN 1
J 0
(-4840 3030);
DISPLAY 0.489362 (-4840 3030);
PAINT MONO (-4840 3030);
FORCEPROP 1 LASTPIN (-4850 2850) $PN 2
J 0
(-4840 2830);
DISPLAY 0.489362 (-4840 2830);
PAINT MONO (-4840 2830);
FORCEPROP 1 LAST VOLTAGE 50V
J 0
(-4800 2950);
DISPLAY 0.489362 (-4800 2950);
PAINT SKYBLUE (-4800 2950);
FORCEPROP 1 LAST PACK_TYPE 0402
J 0
(-4800 2750);
DISPLAY 0.489362 (-4800 2750);
PAINT SKYBLUE (-4800 2750);
FORCEPROP 1 LAST VALUE 1000PF
J 0
(-4800 3000);
DISPLAY 0.489362 (-4800 3000);
PAINT SKYBLUE (-4800 3000);
FORCEPROP 1 LAST TOLERANCE 5%
J 0
(-4800 2900);
DISPLAY 0.489362 (-4800 2900);
PAINT SKYBLUE (-4800 2900);
FORCEPROP 1 LAST MATERIAL X7R
J 0
(-4800 2850);
DISPLAY 0.489362 (-4800 2850);
PAINT SKYBLUE (-4800 2850);
FORCEPROP 2 LAST CDS_LIB pure_quanta
J 0
(-4850 2950);
DISPLAY INVISIBLE (-4850 2950);
FORCEPROP 1 LAST PATH I13
J 0
(-4800 3100);
DISPLAY 0.978723 (-4800 3100);
PAINT WHITE (-4800 3100);
DISPLAY INVISIBLE (-4800 3100);
FORCEPROP 1 LAST PART_NUMBER TMP_QCH21006JB10
J 0
(-4800 2800);
DISPLAY 0.489362 (-4800 2800);
PAINT SKYBLUE (-4800 2800);
DISPLAY INVISIBLE (-4800 2800);
FORCEADD VCC_CORE..1
(1175 8150);
FORCEPROP 3 LASTPIN (1175 8100) SIG_NAME P3V3_AUX\g
J 0
(1185 8110);
DISPLAY 0.659574 (1185 8110);
PAINT MONO (1185 8110);
DISPLAY INVISIBLE (1185 8110);
FORCEPROP 1 LAST HDL_POWER P3V3_AUX
J 1
(1175 8200);
DISPLAY 0.489362 (1175 8200);
PAINT GREEN (1175 8200);
FORCEPROP 2 LAST CDS_LIB pure_quanta_power
J 0
(1175 8150);
DISPLAY INVISIBLE (1175 8150);
FORCEPROP 1 LAST PATH I130
J 0
(1225 8175);
DISPLAY 0.872340 (1225 8175);
PAINT AQUA (1225 8175);
DISPLAY INVISIBLE (1225 8175);
FORCEADD VCC_CORE..1
(-4325 2725);
FORCEPROP 3 LASTPIN (-4325 2675) SIG_NAME P5V_AUX\g
J 0
(-4315 2685);
DISPLAY 0.659574 (-4315 2685);
PAINT MONO (-4315 2685);
DISPLAY INVISIBLE (-4315 2685);
FORCEPROP 1 LAST HDL_POWER P5V_AUX
J 1
(-4325 2775);
DISPLAY 0.489362 (-4325 2775);
PAINT GREEN (-4325 2775);
FORCEPROP 2 LAST CDS_LIB pure_quanta_power
J 0
(-4325 2725);
DISPLAY INVISIBLE (-4325 2725);
FORCEPROP 1 LAST PATH I131
J 0
(-4275 2750);
DISPLAY 0.872340 (-4275 2750);
PAINT AQUA (-4275 2750);
DISPLAY INVISIBLE (-4275 2750);
FORCEADD Q_CAP..2
(-2450 3500);
FORCEPROP 1 LAST LOCATION PC247
J 1
(-2450 3550);
DISPLAY 0.489362 (-2450 3550);
PAINT SKYBLUE (-2450 3550);
FORCEPROP 0 LAST $SEC 1
J 0
(-1875 3575);
DISPLAY 0.680851 (-1875 3575);
PAINT MONO (-1875 3575);
DISPLAY INVISIBLE (-1875 3575);
FORCEPROP 0 LAST CDS_SEC 1
J 0
(-1875 3575);
DISPLAY 1.021277 (-1875 3575);
DISPLAY INVISIBLE (-1875 3575);
FORCEPROP 1 LASTPIN (-2550 3500) $PN 1
J 0
(-2560 3515);
DISPLAY 0.489362 (-2560 3515);
PAINT MONO (-2560 3515);
FORCEPROP 1 LASTPIN (-2350 3500) $PN 2
J 0
(-2365 3515);
DISPLAY 0.489362 (-2365 3515);
PAINT MONO (-2365 3515);
FORCEPROP 1 LAST PACK_TYPE 0402
J 1
(-2275 3425);
DISPLAY 0.489362 (-2275 3425);
PAINT SKYBLUE (-2275 3425);
FORCEPROP 1 LAST VOLTAGE 6.3V
J 0
(-2300 3550);
DISPLAY 0.489362 (-2300 3550);
PAINT SKYBLUE (-2300 3550);
FORCEPROP 1 LAST MATERIAL X7R
J 0
(-2650 3375);
DISPLAY 0.489362 (-2650 3375);
PAINT SKYBLUE (-2650 3375);
FORCEPROP 1 LAST TOLERANCE 10%
J 2
(-2225 3375);
DISPLAY 0.489362 (-2225 3375);
PAINT SKYBLUE (-2225 3375);
FORCEPROP 1 LAST VALUE 1UF
J 2
(-2600 3550);
DISPLAY 0.489362 (-2600 3550);
PAINT SKYBLUE (-2600 3550);
FORCEPROP 2 LAST CDS_LIB pure_quanta
J 0
(-2450 3500);
DISPLAY INVISIBLE (-2450 3500);
FORCEPROP 1 LAST PATH I132
J 0
(-2450 3700);
DISPLAY 0.978723 (-2450 3700);
PAINT WHITE (-2450 3700);
DISPLAY INVISIBLE (-2450 3700);
FORCEPROP 1 LAST PART_NUMBER CH5101K1B01
J 1
(-2575 3425);
DISPLAY 0.489362 (-2575 3425);
PAINT SKYBLUE (-2575 3425);
DISPLAY INVISIBLE (-2575 3425);
FORCEADD RAA229620GNPHA0..1
(-1075 5125);
FORCEPROP 1 LAST LOCATION PU25
J 0
(-1625 8150);
DISPLAY 0.489362 (-1625 8150);
PAINT SKYBLUE (-1625 8150);
FORCEPROP 2 LAST SEC 1
J 0
(-1625 8325);
DISPLAY 0.680851 (-1625 8325);
PAINT MONO (-1625 8325);
DISPLAY INVISIBLE (-1625 8325);
FORCEPROP 2 LASTPIN (-425 3475) $PN 38
J 0
(-415 3485);
DISPLAY 0.489362 (-415 3485);
PAINT MONO (-415 3485);
FORCEPROP 2 LASTPIN (-425 3775) $PN 37
J 0
(-415 3785);
DISPLAY 0.489362 (-415 3785);
PAINT MONO (-415 3785);
FORCEPROP 2 LASTPIN (-425 4075) $PN 36
J 0
(-415 4085);
DISPLAY 0.489362 (-415 4085);
PAINT MONO (-415 4085);
FORCEPROP 2 LASTPIN (-425 4375) $PN 35
J 0
(-415 4385);
DISPLAY 0.489362 (-415 4385);
PAINT MONO (-415 4385);
FORCEPROP 2 LASTPIN (-425 4675) $PN 34
J 0
(-415 4685);
DISPLAY 0.489362 (-415 4685);
PAINT MONO (-415 4685);
FORCEPROP 2 LASTPIN (-425 4975) $PN 33
J 0
(-415 4985);
DISPLAY 0.489362 (-415 4985);
PAINT MONO (-415 4985);
FORCEPROP 2 LASTPIN (-425 5275) $PN 32
J 0
(-415 5285);
DISPLAY 0.489362 (-415 5285);
PAINT MONO (-415 5285);
FORCEPROP 2 LASTPIN (-425 5575) $PN 31
J 0
(-415 5585);
DISPLAY 0.489362 (-415 5585);
PAINT MONO (-415 5585);
FORCEPROP 2 LASTPIN (-425 5875) $PN 30
J 0
(-415 5885);
DISPLAY 0.489362 (-415 5885);
PAINT MONO (-415 5885);
FORCEPROP 2 LASTPIN (-425 6175) $PN 29
J 0
(-415 6185);
DISPLAY 0.489362 (-415 6185);
PAINT MONO (-415 6185);
FORCEPROP 2 LASTPIN (-425 6475) $PN 28
J 0
(-415 6485);
DISPLAY 0.489362 (-415 6485);
PAINT MONO (-415 6485);
FORCEPROP 2 LASTPIN (-425 6775) $PN 27
J 0
(-415 6785);
DISPLAY 0.489362 (-415 6785);
PAINT MONO (-415 6785);
FORCEPROP 2 LASTPIN (-1775 7725) $PN 17
J 2
(-1785 7735);
DISPLAY 0.489362 (-1785 7735);
PAINT MONO (-1785 7735);
FORCEPROP 2 LASTPIN (-1775 3125) $PN 42
J 2
(-1785 3135);
DISPLAY 0.489362 (-1785 3135);
PAINT MONO (-1785 3135);
FORCEPROP 2 LASTPIN (-1775 6425) $PN 15
J 2
(-1785 6435);
DISPLAY 0.489362 (-1785 6435);
PAINT MONO (-1785 6435);
FORCEPROP 2 LASTPIN (-1775 3875) $PN 41
J 2
(-1785 3885);
DISPLAY 0.489362 (-1785 3885);
PAINT MONO (-1785 3885);
FORCEPROP 2 LASTPIN (-1775 7875) $PN 16
J 2
(-1785 7885);
DISPLAY 0.489362 (-1785 7885);
PAINT MONO (-1785 7885);
FORCEPROP 2 LASTPIN (-1775 2625) $PN 20
J 2
(-1785 2635);
DISPLAY 0.489362 (-1785 2635);
PAINT MONO (-1785 2635);
FORCEPROP 2 LASTPIN (-1775 6725) $PN 14
J 2
(-1785 6735);
DISPLAY 0.489362 (-1785 6735);
PAINT MONO (-1785 6735);
FORCEPROP 2 LASTPIN (-1775 6575) $PN 13
J 2
(-1785 6585);
DISPLAY 0.489362 (-1785 6585);
PAINT MONO (-1785 6585);
FORCEPROP 2 LASTPIN (-425 3575) $PN 1
J 0
(-415 3585);
DISPLAY 0.489362 (-415 3585);
PAINT MONO (-415 3585);
FORCEPROP 2 LASTPIN (-425 3875) $PN 2
J 0
(-415 3885);
DISPLAY 0.489362 (-415 3885);
PAINT MONO (-415 3885);
FORCEPROP 2 LASTPIN (-425 4175) $PN 3
J 0
(-415 4185);
DISPLAY 0.489362 (-415 4185);
PAINT MONO (-415 4185);
FORCEPROP 2 LASTPIN (-425 4475) $PN 4
J 0
(-415 4485);
DISPLAY 0.489362 (-415 4485);
PAINT MONO (-415 4485);
FORCEPROP 2 LASTPIN (-425 4775) $PN 5
J 0
(-415 4785);
DISPLAY 0.489362 (-415 4785);
PAINT MONO (-415 4785);
FORCEPROP 2 LASTPIN (-425 5075) $PN 6
J 0
(-415 5085);
DISPLAY 0.489362 (-415 5085);
PAINT MONO (-415 5085);
FORCEPROP 2 LASTPIN (-425 5375) $PN 7
J 0
(-415 5385);
DISPLAY 0.489362 (-415 5385);
PAINT MONO (-415 5385);
FORCEPROP 2 LASTPIN (-425 5675) $PN 8
J 0
(-415 5685);
DISPLAY 0.489362 (-415 5685);
PAINT MONO (-415 5685);
FORCEPROP 2 LASTPIN (-425 5975) $PN 9
J 0
(-415 5985);
DISPLAY 0.489362 (-415 5985);
PAINT MONO (-415 5985);
FORCEPROP 2 LASTPIN (-425 6275) $PN 10
J 0
(-415 6285);
DISPLAY 0.489362 (-415 6285);
PAINT MONO (-415 6285);
FORCEPROP 2 LASTPIN (-425 6575) $PN 11
J 0
(-415 6585);
DISPLAY 0.489362 (-415 6585);
PAINT MONO (-415 6585);
FORCEPROP 2 LASTPIN (-425 6875) $PN 12
J 0
(-415 6885);
DISPLAY 0.489362 (-415 6885);
PAINT MONO (-415 6885);
FORCEPROP 2 LASTPIN (-1775 4025) $PN 18
J 2
(-1785 4035);
DISPLAY 0.489362 (-1785 4035);
PAINT MONO (-1785 4035);
FORCEPROP 2 LASTPIN (-1775 5575) $PN 26
J 2
(-1785 5585);
DISPLAY 0.489362 (-1785 5585);
PAINT MONO (-1785 5585);
FORCEPROP 2 LASTPIN (-1775 4475) $PN 39
J 2
(-1785 4485);
DISPLAY 0.489362 (-1785 4485);
PAINT MONO (-1785 4485);
FORCEPROP 2 LASTPIN (-1775 7425) $PN 22
J 2
(-1785 7435);
DISPLAY 0.489362 (-1785 7435);
PAINT MONO (-1785 7435);
FORCEPROP 2 LASTPIN (-1775 7275) $PN 21
J 2
(-1785 7285);
DISPLAY 0.489362 (-1785 7285);
PAINT MONO (-1785 7285);
FORCEPROP 2 LASTPIN (-1775 6975) $PN 24
J 2
(-1785 6985);
DISPLAY 0.489362 (-1785 6985);
PAINT MONO (-1785 6985);
FORCEPROP 2 LASTPIN (-1775 7125) $PN 23
J 2
(-1785 7135);
DISPLAY 0.489362 (-1785 7135);
PAINT MONO (-1785 7135);
FORCEPROP 2 LASTPIN (-425 2675) $PN 44
J 0
(-415 2685);
DISPLAY 0.489362 (-415 2685);
PAINT MONO (-415 2685);
FORCEPROP 2 LASTPIN (-425 2975) $PN 43
J 0
(-415 2985);
DISPLAY 0.489362 (-415 2985);
PAINT MONO (-415 2985);
FORCEPROP 2 LASTPIN (-1775 2325) $PN TH
J 2
(-1785 2335);
DISPLAY 0.489362 (-1785 2335);
PAINT MONO (-1785 2335);
FORCEPROP 2 LASTPIN (-425 7875) $PN 47
J 0
(-415 7885);
DISPLAY 0.489362 (-415 7885);
PAINT MONO (-415 7885);
FORCEPROP 2 LASTPIN (-425 7575) $PN 48
J 0
(-415 7585);
DISPLAY 0.489362 (-415 7585);
PAINT MONO (-415 7585);
FORCEPROP 2 LASTPIN (-1775 3625) $PN 19
J 2
(-1785 3635);
DISPLAY 0.489362 (-1785 3635);
PAINT MONO (-1785 3635);
FORCEPROP 2 LASTPIN (-1775 2425) $PN 46
J 2
(-1785 2435);
DISPLAY 0.489362 (-1785 2435);
PAINT MONO (-1785 2435);
FORCEPROP 2 LASTPIN (-1775 2525) $PN 45
J 2
(-1785 2535);
DISPLAY 0.489362 (-1785 2535);
PAINT MONO (-1785 2535);
FORCEPROP 2 LASTPIN (-1775 5825) $PN 25
J 2
(-1785 5835);
DISPLAY 0.489362 (-1785 5835);
PAINT MONO (-1785 5835);
FORCEPROP 2 LASTPIN (-1775 4725) $PN 40
J 2
(-1785 4735);
DISPLAY 0.489362 (-1785 4735);
PAINT MONO (-1785 4735);
FORCEPROP 1 LAST MATERIAL IC
J 0
(-1625 8000);
DISPLAY 0.489362 (-1625 8000);
PAINT SKYBLUE (-1625 8000);
FORCEPROP 2 LAST PART_TYPE SMLF
J 0
(-1625 8275);
DISPLAY 1.021277 (-1625 8275);
FORCEPROP 2 LAST VALUE RAA229620GNP#HA0
J 0
(-1625 8225);
DISPLAY 0.489362 (-1625 8225);
PAINT SKYBLUE (-1625 8225);
FORCEPROP 2 LAST CDS_LIB pure_quanta
J 0
(-1075 5125);
DISPLAY INVISIBLE (-1075 5125);
FORCEPROP 1 LAST NEEDS_NO_SIZE TRUE
J 0
(-1075 5125);
DISPLAY 0.723404 (-1075 5125);
PAINT GREEN (-1075 5125);
DISPLAY INVISIBLE (-1075 5125);
FORCEPROP 1 LAST CDS_LMAN_SYM_OUTLINE -550,2850,500,-2850
J 0
(-1075 5125);
DISPLAY 0.468085 (-1075 5125);
PAINT GREEN (-1075 5125);
DISPLAY INVISIBLE (-1075 5125);
FORCEPROP 2 LAST SEC_TYPE 
J 0
(-1625 8325);
DISPLAY 1.021277 (-1625 8325);
DISPLAY INVISIBLE (-1625 8325);
FORCEPROP 1 LAST PATH I133
J 0
(-1075 5125);
DISPLAY 0.723404 (-1075 5125);
PAINT GREEN (-1075 5125);
DISPLAY INVISIBLE (-1075 5125);
FORCEPROP 1 LAST PART_NUMBER ARF0TGP4002
J 0
(-1625 8075);
DISPLAY 0.489362 (-1625 8075);
PAINT SKYBLUE (-1625 8075);
DISPLAY INVISIBLE (-1625 8075);
FORCEADD Q_RES..2
(-5075 2950);
FORCEPROP 1 LAST LOCATION R6087
J 0
(-5325 3050);
DISPLAY 0.404255 (-5325 3050);
FORCEPROP 0 LAST $SEC 1
J 0
(-5325 3075);
DISPLAY 0.680851 (-5325 3075);
PAINT MONO (-5325 3075);
DISPLAY INVISIBLE (-5325 3075);
FORCEPROP 0 LAST CDS_SEC 1
J 0
(-5325 3075);
DISPLAY 0.680851 (-5325 3075);
DISPLAY INVISIBLE (-5325 3075);
FORCEPROP 1 LASTPIN (-5075 3050) $PN 1
J 0
(-5070 3012);
DISPLAY 0.787234 (-5070 3012);
PAINT MONO (-5070 3012);
FORCEPROP 1 LASTPIN (-5075 2850) $PN 2
J 0
(-5070 2860);
DISPLAY 0.787234 (-5070 2860);
PAINT MONO (-5070 2860);
FORCEPROP 1 LAST VALUE 10K
J 0
(-5325 3000);
DISPLAY 0.404255 (-5325 3000);
FORCEPROP 1 LAST PACK_TYPE 0402LF
J 0
(-5325 2750);
DISPLAY 0.404255 (-5325 2750);
FORCEPROP 1 LAST WATTAGE 1/16W
J 0
(-5325 2900);
DISPLAY 0.404255 (-5325 2900);
FORCEPROP 1 LAST TOLERANCE 1%
J 0
(-5320 2950);
DISPLAY 0.404255 (-5320 2950);
FORCEPROP 1 LAST MATERIAL EMPTY
J 0
(-5325 2850);
DISPLAY 0.404255 (-5325 2850);
FORCEPROP 2 LAST CDS_LIB pure_quanta
J 0
(-5075 2950);
DISPLAY INVISIBLE (-5075 2950);
FORCEPROP 1 LAST PATH I135
J 0
(-5025 3125);
DISPLAY 0.978723 (-5025 3125);
PAINT WHITE (-5025 3125);
DISPLAY INVISIBLE (-5025 3125);
FORCEPROP 1 LAST PART_NUMBER CS31002FB08
J 0
(-5325 2800);
DISPLAY 0.404255 (-5325 2800);
DISPLAY INVISIBLE (-5325 2800);
FORCEADD UNIVERSAL_GND..1
R 7
(-4200 2900);
FORCEPROP 3 LASTPIN (-4150 2900) SIG_NAME GND\g
J 0
(-4140 2910);
DISPLAY 0.659574 (-4140 2910);
PAINT MONO (-4140 2910);
DISPLAY INVISIBLE (-4140 2910);
FORCEPROP 2 LAST CDS_LIB pure_quanta_power
R 1
J 0
(-4200 2900);
DISPLAY INVISIBLE (-4200 2900);
FORCEPROP 1 LAST HDL_POWER GND
R 1
J 1
(-4275 2925);
DISPLAY 0.872340 (-4275 2925);
PAINT GREEN (-4275 2925);
DISPLAY INVISIBLE (-4275 2925);
FORCEPROP 1 LAST PATH I136
R 1
J 0
(-4200 2975);
DISPLAY 0.872340 (-4200 2975);
PAINT AQUA (-4200 2975);
DISPLAY INVISIBLE (-4200 2975);
FORCEADD Q_CAP..2
(-3900 2900);
FORCEPROP 1 LAST LOCATION C5019
J 1
(-4075 2900);
DISPLAY 0.489362 (-4075 2900);
PAINT SKYBLUE (-4075 2900);
FORCEPROP 0 LAST $SEC 1
J 0
(-3950 3000);
DISPLAY 0.680851 (-3950 3000);
PAINT MONO (-3950 3000);
DISPLAY INVISIBLE (-3950 3000);
FORCEPROP 0 LAST CDS_SEC 1
J 0
(-3950 3000);
DISPLAY 1.021277 (-3950 3000);
DISPLAY INVISIBLE (-3950 3000);
FORCEPROP 1 LASTPIN (-4000 2900) $PN 1
J 0
(-4010 2915);
DISPLAY 0.489362 (-4010 2915);
PAINT MONO (-4010 2915);
FORCEPROP 1 LASTPIN (-3800 2900) $PN 2
J 0
(-3815 2915);
DISPLAY 0.489362 (-3815 2915);
PAINT MONO (-3815 2915);
FORCEPROP 1 LAST MATERIAL X7R
J 0
(-4150 2950);
DISPLAY 0.489362 (-4150 2950);
PAINT SKYBLUE (-4150 2950);
FORCEPROP 1 LAST VOLTAGE 50V
J 0
(-4325 2950);
DISPLAY 0.489362 (-4325 2950);
PAINT SKYBLUE (-4325 2950);
FORCEPROP 1 LAST VALUE 1000PF
J 2
(-3625 2900);
DISPLAY 0.489362 (-3625 2900);
PAINT SKYBLUE (-3625 2900);
FORCEPROP 1 LAST PACK_TYPE 0402
J 1
(-4000 2950);
DISPLAY 0.489362 (-4000 2950);
PAINT SKYBLUE (-4000 2950);
FORCEPROP 1 LAST TOLERANCE 5%
J 2
(-4175 2950);
DISPLAY 0.489362 (-4175 2950);
PAINT SKYBLUE (-4175 2950);
FORCEPROP 2 LAST CDS_LIB pure_quanta
J 0
(-3900 2900);
DISPLAY INVISIBLE (-3900 2900);
FORCEPROP 1 LAST PATH I137
J 0
(-3900 3100);
DISPLAY 0.978723 (-3900 3100);
PAINT WHITE (-3900 3100);
DISPLAY INVISIBLE (-3900 3100);
FORCEPROP 1 LAST PART_NUMBER TMP_QCH21006JB10
J 1
(-4150 2975);
DISPLAY 0.489362 (-4150 2975);
PAINT SKYBLUE (-4150 2975);
DISPLAY INVISIBLE (-4150 2975);
FORCEADD UNIVERSAL_GND..1
(-3125 6050);
FORCEPROP 3 LASTPIN (-3125 6100) SIG_NAME GND\g
J 0
(-3115 6110);
DISPLAY 0.659574 (-3115 6110);
PAINT MONO (-3115 6110);
DISPLAY INVISIBLE (-3115 6110);
FORCEPROP 2 LAST CDS_LIB pure_quanta_power
J 0
(-3125 6050);
PAINT MONO (-3125 6050);
DISPLAY INVISIBLE (-3125 6050);
FORCEPROP 1 LAST HDL_POWER GND
J 1
(-3100 5975);
DISPLAY 0.872340 (-3100 5975);
PAINT GREEN (-3100 5975);
DISPLAY INVISIBLE (-3100 5975);
FORCEPROP 1 LAST PATH I138
J 0
(-3050 6050);
DISPLAY 0.872340 (-3050 6050);
PAINT AQUA (-3050 6050);
DISPLAY INVISIBLE (-3050 6050);
FORCEADD Q_CAP..1
(-3125 6250);
FORCEPROP 1 LAST LOCATION C5012
J 0
(-3025 6250);
DISPLAY 0.510638 (-3025 6250);
FORCEPROP 0 LAST $SEC 1
J 0
(-2875 6275);
DISPLAY 0.680851 (-2875 6275);
PAINT MONO (-2875 6275);
DISPLAY INVISIBLE (-2875 6275);
FORCEPROP 0 LAST CDS_SEC 1
J 0
(-2875 6275);
DISPLAY 0.680851 (-2875 6275);
DISPLAY INVISIBLE (-2875 6275);
FORCEPROP 1 LASTPIN (-3125 6350) $PN 1
J 0
(-3115 6330);
DISPLAY 0.787234 (-3115 6330);
PAINT MONO (-3115 6330);
FORCEPROP 1 LASTPIN (-3125 6150) $PN 2
J 0
(-3115 6130);
DISPLAY 0.787234 (-3115 6130);
PAINT MONO (-3115 6130);
FORCEPROP 1 LAST VALUE 1000PF
J 0
(-3050 6225);
DISPLAY 0.510638 (-3050 6225);
FORCEPROP 1 LAST VOLTAGE 50V
J 0
(-2875 6175);
DISPLAY 0.510638 (-2875 6175);
FORCEPROP 1 LAST TOLERANCE 5%
J 0
(-2875 6150);
DISPLAY 0.510638 (-2875 6150);
FORCEPROP 1 LAST MATERIAL X7R
J 0
(-2875 6200);
DISPLAY 0.510638 (-2875 6200);
FORCEPROP 1 LAST PACK_TYPE 0402
J 0
(-2875 6225);
DISPLAY 0.510638 (-2875 6225);
FORCEPROP 2 LAST CDS_LIB pure_quanta
J 0
(-3125 6250);
DISPLAY INVISIBLE (-3125 6250);
FORCEPROP 1 LAST PATH I139
J 0
(-3075 6400);
DISPLAY 0.978723 (-3075 6400);
PAINT WHITE (-3075 6400);
DISPLAY INVISIBLE (-3075 6400);
FORCEPROP 1 LAST PART_NUMBER TMP_QCH21006JB10
J 0
(-2875 6250);
DISPLAY 0.510638 (-2875 6250);
DISPLAY INVISIBLE (-2875 6250);
FORCEADD Q_RES..1
(-4025 2600);
FORCEPROP 1 LAST LOCATION PR157
J 0
(-4075 2650);
DISPLAY 0.489362 (-4075 2650);
PAINT SKYBLUE (-4075 2650);
FORCEPROP 0 LAST $SEC 1
J 0
(-4075 2700);
DISPLAY 0.680851 (-4075 2700);
PAINT MONO (-4075 2700);
DISPLAY INVISIBLE (-4075 2700);
FORCEPROP 0 LAST CDS_SEC 1
J 0
(-4075 2700);
DISPLAY 1.021277 (-4075 2700);
DISPLAY INVISIBLE (-4075 2700);
FORCEPROP 1 LASTPIN (-4125 2600) $PN 1
J 0
(-4113 2612);
DISPLAY 0.489362 (-4113 2612);
PAINT MONO (-4113 2612);
FORCEPROP 1 LASTPIN (-3925 2600) $PN 2
J 0
(-3963 2612);
DISPLAY 0.489362 (-3963 2612);
PAINT MONO (-3963 2612);
FORCEPROP 1 LAST VALUE 40.2K
J 2
(-4175 2625);
DISPLAY 0.489362 (-4175 2625);
PAINT SKYBLUE (-4175 2625);
FORCEPROP 1 LAST TOLERANCE 1%
J 0
(-3875 2625);
DISPLAY 0.489362 (-3875 2625);
PAINT SKYBLUE (-3875 2625);
FORCEPROP 1 LAST MATERIAL CHIP
J 0
(-4325 2525);
DISPLAY 0.489362 (-4325 2525);
PAINT SKYBLUE (-4325 2525);
FORCEPROP 1 LAST WATTAGE 1/16W
J 0
(-3900 2550);
DISPLAY 0.489362 (-3900 2550);
PAINT SKYBLUE (-3900 2550);
FORCEPROP 1 LAST PACK_TYPE 0402LF
J 0
(-3900 2525);
DISPLAY 0.489362 (-3900 2525);
PAINT SKYBLUE (-3900 2525);
FORCEPROP 2 LAST CDS_LIB pure_quanta
J 0
(-4025 2600);
DISPLAY INVISIBLE (-4025 2600);
FORCEPROP 1 LAST PATH I14
J 0
(-4075 2750);
DISPLAY 0.978723 (-4075 2750);
PAINT WHITE (-4075 2750);
DISPLAY INVISIBLE (-4075 2750);
FORCEPROP 1 LAST PART_NUMBER CS34022FB04
J 0
(-4325 2550);
DISPLAY 0.489362 (-4325 2550);
PAINT SKYBLUE (-4325 2550);
DISPLAY INVISIBLE (-4325 2550);
FORCEADD UNIVERSAL_GND..1
R 7
(-3900 7950);
FORCEPROP 3 LASTPIN (-3850 7950) SIG_NAME GND\g
J 0
(-3840 7960);
DISPLAY 0.659574 (-3840 7960);
PAINT MONO (-3840 7960);
DISPLAY INVISIBLE (-3840 7960);
FORCEPROP 2 LAST CDS_LIB pure_quanta_power
R 1
J 0
(-3900 7950);
DISPLAY INVISIBLE (-3900 7950);
FORCEPROP 1 LAST HDL_POWER GND
R 1
J 1
(-3975 7975);
DISPLAY 0.872340 (-3975 7975);
PAINT GREEN (-3975 7975);
DISPLAY INVISIBLE (-3975 7975);
FORCEPROP 1 LAST PATH I140
R 1
J 0
(-3900 8025);
DISPLAY 0.872340 (-3900 8025);
PAINT AQUA (-3900 8025);
DISPLAY INVISIBLE (-3900 8025);
FORCEADD Q_CAP..2
(-3600 7950);
FORCEPROP 1 LAST LOCATION C5003
J 1
(-3775 7950);
DISPLAY 0.489362 (-3775 7950);
PAINT SKYBLUE (-3775 7950);
FORCEPROP 0 LAST $SEC 1
J 0
(-3650 8050);
DISPLAY 0.680851 (-3650 8050);
PAINT MONO (-3650 8050);
DISPLAY INVISIBLE (-3650 8050);
FORCEPROP 0 LAST CDS_SEC 1
J 0
(-3650 8050);
DISPLAY 1.021277 (-3650 8050);
DISPLAY INVISIBLE (-3650 8050);
FORCEPROP 1 LASTPIN (-3700 7950) $PN 1
J 0
(-3710 7965);
DISPLAY 0.489362 (-3710 7965);
PAINT MONO (-3710 7965);
FORCEPROP 1 LASTPIN (-3500 7950) $PN 2
J 0
(-3515 7965);
DISPLAY 0.489362 (-3515 7965);
PAINT MONO (-3515 7965);
FORCEPROP 1 LAST VALUE 1000PF
J 2
(-3325 7950);
DISPLAY 0.489362 (-3325 7950);
PAINT SKYBLUE (-3325 7950);
FORCEPROP 1 LAST VOLTAGE 50V
J 0
(-3725 8025);
DISPLAY 0.489362 (-3725 8025);
PAINT SKYBLUE (-3725 8025);
FORCEPROP 1 LAST TOLERANCE 5%
J 2
(-3775 8025);
DISPLAY 0.489362 (-3775 8025);
PAINT SKYBLUE (-3775 8025);
FORCEPROP 1 LAST MATERIAL X7R
J 0
(-3850 8000);
DISPLAY 0.489362 (-3850 8000);
PAINT SKYBLUE (-3850 8000);
FORCEPROP 1 LAST PACK_TYPE 0402
J 1
(-3700 8000);
DISPLAY 0.489362 (-3700 8000);
PAINT SKYBLUE (-3700 8000);
FORCEPROP 2 LAST CDS_LIB pure_quanta
J 0
(-3600 7950);
DISPLAY INVISIBLE (-3600 7950);
FORCEPROP 1 LAST PATH I141
J 0
(-3600 8150);
DISPLAY 0.978723 (-3600 8150);
PAINT WHITE (-3600 8150);
DISPLAY INVISIBLE (-3600 8150);
FORCEPROP 1 LAST PART_NUMBER TMP_QCH21006JB10
J 1
(-3700 8075);
DISPLAY 0.489362 (-3700 8075);
PAINT SKYBLUE (-3700 8075);
DISPLAY INVISIBLE (-3700 8075);
FORCEADD Q_RES..2
(-3875 3150);
FORCEPROP 1 LAST LOCATION PR159
J 0
(-3850 3225);
DISPLAY 0.510638 (-3850 3225);
FORCEPROP 0 LAST $SEC 1
J 0
(-3850 3250);
DISPLAY 0.680851 (-3850 3250);
PAINT MONO (-3850 3250);
DISPLAY INVISIBLE (-3850 3250);
FORCEPROP 0 LAST CDS_SEC 1
J 0
(-3850 3250);
DISPLAY 0.680851 (-3850 3250);
DISPLAY INVISIBLE (-3850 3250);
FORCEPROP 1 LASTPIN (-3875 3250) $PN 1
J 0
(-3870 3212);
DISPLAY 0.787234 (-3870 3212);
PAINT MONO (-3870 3212);
FORCEPROP 1 LASTPIN (-3875 3050) $PN 2
J 0
(-3870 3060);
DISPLAY 0.787234 (-3870 3060);
PAINT MONO (-3870 3060);
FORCEPROP 1 LAST PACK_TYPE 0402LF
J 0
(-3850 3075);
DISPLAY 0.510638 (-3850 3075);
FORCEPROP 1 LAST MATERIAL CHIP
J 0
(-3850 3125);
DISPLAY 0.510638 (-3850 3125);
FORCEPROP 1 LAST WATTAGE 1/16W
J 0
(-3850 3150);
DISPLAY 0.510638 (-3850 3150);
FORCEPROP 1 LAST TOLERANCE 1%
J 0
(-3850 3175);
DISPLAY 0.510638 (-3850 3175);
FORCEPROP 1 LAST VALUE 5.23K
J 0
(-3850 3200);
DISPLAY 0.510638 (-3850 3200);
FORCEPROP 2 LAST CDS_LIB pure_quanta
J 0
(-3875 3150);
DISPLAY INVISIBLE (-3875 3150);
FORCEPROP 1 LAST PATH I142
J 0
(-3825 3325);
DISPLAY 0.978723 (-3825 3325);
PAINT WHITE (-3825 3325);
DISPLAY INVISIBLE (-3825 3325);
FORCEPROP 1 LAST PART_NUMBER CS25232FB08
J 0
(-3850 3100);
DISPLAY 0.510638 (-3850 3100);
DISPLAY INVISIBLE (-3850 3100);
FORCEADD Q_RES..1
(-2800 7425);
FORCEPROP 1 LAST LOCATION PR8009
J 0
(-2850 7475);
DISPLAY 0.489362 (-2850 7475);
PAINT SKYBLUE (-2850 7475);
FORCEPROP 0 LAST $SEC 1
J 0
(-2850 7500);
DISPLAY 0.680851 (-2850 7500);
PAINT MONO (-2850 7500);
DISPLAY INVISIBLE (-2850 7500);
FORCEPROP 0 LAST CDS_SEC 1
J 0
(-2850 7500);
DISPLAY 0.680851 (-2850 7500);
DISPLAY INVISIBLE (-2850 7500);
FORCEPROP 1 LASTPIN (-2900 7425) $PN 1
J 0
(-2888 7437);
DISPLAY 0.787234 (-2888 7437);
PAINT MONO (-2888 7437);
FORCEPROP 1 LASTPIN (-2700 7425) $PN 2
J 0
(-2738 7437);
DISPLAY 0.787234 (-2738 7437);
PAINT MONO (-2738 7437);
FORCEPROP 1 LAST WATTAGE 1/16W
J 0
(-2700 7375);
DISPLAY 0.489362 (-2700 7375);
PAINT SKYBLUE (-2700 7375);
FORCEPROP 1 LAST PACK_TYPE 0402LF
J 0
(-2700 7350);
DISPLAY 0.489362 (-2700 7350);
PAINT SKYBLUE (-2700 7350);
FORCEPROP 1 LAST VALUE 0
J 2
(-2925 7450);
DISPLAY 0.489362 (-2925 7450);
PAINT SKYBLUE (-2925 7450);
FORCEPROP 1 LAST MATERIAL CHIP
J 0
(-3050 7350);
DISPLAY 0.489362 (-3050 7350);
PAINT SKYBLUE (-3050 7350);
FORCEPROP 1 LAST TOLERANCE 5%
J 0
(-2675 7450);
DISPLAY 0.489362 (-2675 7450);
PAINT SKYBLUE (-2675 7450);
FORCEPROP 2 LAST CDS_LIB pure_quanta
J 0
(-2800 7425);
DISPLAY INVISIBLE (-2800 7425);
FORCEPROP 1 LAST PATH I143
J 0
(-2850 7575);
DISPLAY 0.978723 (-2850 7575);
PAINT WHITE (-2850 7575);
DISPLAY INVISIBLE (-2850 7575);
FORCEPROP 1 LAST PART_NUMBER CS00002JB13
J 0
(-3050 7375);
DISPLAY 0.489362 (-3050 7375);
PAINT SKYBLUE (-3050 7375);
DISPLAY INVISIBLE (-3050 7375);
FORCEADD Q_RES..1
(-2800 7275);
FORCEPROP 1 LAST LOCATION PR8010
J 0
(-2850 7325);
DISPLAY 0.489362 (-2850 7325);
PAINT SKYBLUE (-2850 7325);
FORCEPROP 0 LAST $SEC 1
J 0
(-2850 7350);
DISPLAY 0.680851 (-2850 7350);
PAINT MONO (-2850 7350);
DISPLAY INVISIBLE (-2850 7350);
FORCEPROP 0 LAST CDS_SEC 1
J 0
(-2850 7350);
DISPLAY 0.680851 (-2850 7350);
DISPLAY INVISIBLE (-2850 7350);
FORCEPROP 1 LASTPIN (-2900 7275) $PN 1
J 0
(-2888 7287);
DISPLAY 0.787234 (-2888 7287);
PAINT MONO (-2888 7287);
FORCEPROP 1 LASTPIN (-2700 7275) $PN 2
J 0
(-2738 7287);
DISPLAY 0.787234 (-2738 7287);
PAINT MONO (-2738 7287);
FORCEPROP 1 LAST VALUE 0
J 2
(-2925 7300);
DISPLAY 0.489362 (-2925 7300);
PAINT SKYBLUE (-2925 7300);
FORCEPROP 1 LAST WATTAGE 1/16W
J 0
(-2700 7225);
DISPLAY 0.489362 (-2700 7225);
PAINT SKYBLUE (-2700 7225);
FORCEPROP 1 LAST MATERIAL CHIP
J 0
(-3050 7200);
DISPLAY 0.489362 (-3050 7200);
PAINT SKYBLUE (-3050 7200);
FORCEPROP 1 LAST TOLERANCE 5%
J 0
(-2675 7300);
DISPLAY 0.489362 (-2675 7300);
PAINT SKYBLUE (-2675 7300);
FORCEPROP 1 LAST PACK_TYPE 0402LF
J 0
(-2700 7200);
DISPLAY 0.489362 (-2700 7200);
PAINT SKYBLUE (-2700 7200);
FORCEPROP 2 LAST CDS_LIB pure_quanta
J 0
(-2800 7275);
DISPLAY INVISIBLE (-2800 7275);
FORCEPROP 1 LAST PATH I144
J 0
(-2850 7425);
DISPLAY 0.978723 (-2850 7425);
PAINT WHITE (-2850 7425);
DISPLAY INVISIBLE (-2850 7425);
FORCEPROP 1 LAST PART_NUMBER CS00002JB13
J 0
(-3050 7225);
DISPLAY 0.489362 (-3050 7225);
PAINT SKYBLUE (-3050 7225);
DISPLAY INVISIBLE (-3050 7225);
FORCEADD OFFPAGE..2
R 2
(-3925 2775);
FORCEPROP 2 LAST $XR0 80 
J 0
(-4179 2775);
DISPLAY 0.638298 (-4179 2775);
PAINT MONO (-4179 2775);
FORCEPROP 2 LAST CDS_LIB standard
J 0
(-3925 2775);
DISPLAY INVISIBLE (-3925 2775);
FORCEPROP 1 LAST OFFPAGE TRUE
J 2
(-4250 2650);
DISPLAY 0.872340 (-4250 2650);
PAINT GREEN (-4250 2650);
DISPLAY INVISIBLE (-4250 2650);
FORCEPROP 1 LAST COMMENT_BODY TRUE
J 2
(-3880 2680);
DISPLAY 0.872340 (-3880 2680);
PAINT GREEN (-3880 2680);
DISPLAY INVISIBLE (-3880 2680);
FORCEPROP 2 LAST PATH I15
J 0
(-4175 2825);
DISPLAY 0.680851 (-4175 2825);
DISPLAY INVISIBLE (-4175 2825);
FORCEADD MOSFET_N..1
(-4600 3300);
FORCEPROP 1 LAST LOCATION PQ15
J 0
(-4475 3300);
DISPLAY 0.489362 (-4475 3300);
PAINT SKYBLUE (-4475 3300);
FORCEPROP 0 LAST $SEC 1
J 0
(-4475 3325);
DISPLAY 0.680851 (-4475 3325);
PAINT MONO (-4475 3325);
DISPLAY INVISIBLE (-4475 3325);
FORCEPROP 0 LAST CDS_SEC 1
J 0
(-4475 3325);
DISPLAY 1.021277 (-4475 3325);
DISPLAY INVISIBLE (-4475 3325);
FORCEPROP 1 LASTPIN (-4550 3400) $PN D
R 1
J 0
(-4550 3393);
DISPLAY 0.489362 (-4550 3393);
PAINT MONO (-4550 3393);
FORCEPROP 1 LASTPIN (-4700 3200) $PN G
J 2
(-4690 3203);
DISPLAY 0.489362 (-4690 3203);
PAINT MONO (-4690 3203);
FORCEPROP 1 LASTPIN (-4550 3100) $PN S
R 1
J 2
(-4550 3113);
DISPLAY 0.489362 (-4550 3113);
PAINT MONO (-4550 3113);
FORCEPROP 1 LAST MATERIAL IC
J 0
(-4475 3150);
DISPLAY 0.489362 (-4475 3150);
PAINT SKYBLUE (-4475 3150);
FORCEPROP 1 LAST VALUE BSS138K
J 0
(-4475 3250);
DISPLAY 0.489362 (-4475 3250);
PAINT SKYBLUE (-4475 3250);
FORCEPROP 2 LAST PATH I16
J 0
(-4475 3325);
DISPLAY 0.680851 (-4475 3325);
FORCEPROP 0 LAST MANUF_PN BSS138K
J 0
(-4500 3100);
DISPLAY 1.021277 (-4500 3100);
DISPLAY INVISIBLE (-4500 3100);
FORCEPROP 1 LAST CDS_LMAN_SYM_OUTLINE -50,50,100,-150
J 0
(-4600 3300);
DISPLAY 0.468085 (-4600 3300);
PAINT GREEN (-4600 3300);
DISPLAY INVISIBLE (-4600 3300);
FORCEPROP 2 LAST CDS_LIB pure_quanta
J 0
(-4600 3300);
DISPLAY INVISIBLE (-4600 3300);
FORCEPROP 1 LAST PACK_TYPE SMLF
J 0
(-4575 3050);
DISPLAY 0.723404 (-4575 3050);
PAINT SKYBLUE (-4575 3050);
DISPLAY INVISIBLE (-4575 3050);
FORCEPROP 1 LAST PART_NUMBER BAM138K0000
J 0
(-4475 3200);
DISPLAY 0.489362 (-4475 3200);
PAINT SKYBLUE (-4475 3200);
DISPLAY INVISIBLE (-4475 3200);
FORCEADD Q_RES..2
(-4550 3850);
FORCEPROP 1 LAST LOCATION PR152
J 0
(-4500 3900);
DISPLAY 0.489362 (-4500 3900);
PAINT SKYBLUE (-4500 3900);
FORCEPROP 0 LAST $SEC 1
J 0
(-4525 3925);
DISPLAY 0.680851 (-4525 3925);
PAINT MONO (-4525 3925);
DISPLAY INVISIBLE (-4525 3925);
FORCEPROP 0 LAST CDS_SEC 1
J 0
(-4525 3925);
DISPLAY 1.021277 (-4525 3925);
DISPLAY INVISIBLE (-4525 3925);
FORCEPROP 1 LASTPIN (-4550 3950) $PN 1
J 0
(-4545 3912);
DISPLAY 0.489362 (-4545 3912);
PAINT MONO (-4545 3912);
FORCEPROP 1 LASTPIN (-4550 3750) $PN 2
J 0
(-4545 3760);
DISPLAY 0.489362 (-4545 3760);
PAINT MONO (-4545 3760);
FORCEPROP 1 LAST PACK_TYPE 0402LF
J 0
(-4500 3750);
DISPLAY 0.489362 (-4500 3750);
PAINT SKYBLUE (-4500 3750);
FORCEPROP 1 LAST VALUE 1K
J 0
(-4500 3875);
DISPLAY 0.489362 (-4500 3875);
PAINT SKYBLUE (-4500 3875);
FORCEPROP 1 LAST TOLERANCE 1%
J 0
(-4500 3850);
DISPLAY 0.489362 (-4500 3850);
PAINT SKYBLUE (-4500 3850);
FORCEPROP 1 LAST MATERIAL CHIP
J 0
(-4500 3800);
DISPLAY 0.489362 (-4500 3800);
PAINT SKYBLUE (-4500 3800);
FORCEPROP 1 LAST WATTAGE 1/16W
J 0
(-4500 3825);
DISPLAY 0.489362 (-4500 3825);
PAINT SKYBLUE (-4500 3825);
FORCEPROP 2 LAST CDS_LIB pure_quanta
J 0
(-4550 3850);
DISPLAY INVISIBLE (-4550 3850);
FORCEPROP 1 LAST PATH I17
J 0
(-4500 4025);
DISPLAY 0.978723 (-4500 4025);
PAINT WHITE (-4500 4025);
DISPLAY INVISIBLE (-4500 4025);
FORCEPROP 1 LAST PART_NUMBER CS21002FB06
J 0
(-4500 3775);
DISPLAY 0.489362 (-4500 3775);
PAINT SKYBLUE (-4500 3775);
DISPLAY INVISIBLE (-4500 3775);
FORCEADD MOSFET_PCH_GDS_ESD_PROTECTED..1
R 6
(-3900 3625);
FORCEPROP 1 LAST LOCATION PQ11
J 0
(-3725 3475);
DISPLAY 0.489362 (-3725 3475);
PAINT SKYBLUE (-3725 3475);
FORCEPROP 0 LAST $SEC 1
J 0
(-3725 3650);
DISPLAY 0.680851 (-3725 3650);
PAINT MONO (-3725 3650);
DISPLAY INVISIBLE (-3725 3650);
FORCEPROP 0 LAST CDS_SEC 1
J 0
(-3725 3650);
DISPLAY 1.021277 (-3725 3650);
DISPLAY INVISIBLE (-3725 3650);
FORCEPROP 0 LASTPIN (-3875 3325) $PN D
R 1
J 2
(-3885 3315);
DISPLAY 0.489362 (-3885 3315);
PAINT MONO (-3885 3315);
FORCEPROP 0 LASTPIN (-4175 3625) $PN G
J 2
(-4185 3635);
DISPLAY 0.489362 (-4185 3635);
PAINT MONO (-4185 3635);
FORCEPROP 0 LASTPIN (-3875 3925) $PN S
R 1
J 0
(-3885 3935);
DISPLAY 0.489362 (-3885 3935);
PAINT MONO (-3885 3935);
FORCEPROP 2 LAST VALUE PJA3415AE
J 0
(-3725 3577);
DISPLAY 0.489362 (-3725 3577);
PAINT SKYBLUE (-3725 3577);
FORCEPROP 1 LAST MATERIAL IC
J 0
(-3725 3627);
DISPLAY 0.489362 (-3725 3627);
PAINT SKYBLUE (-3725 3627);
FORCEPROP 2 LAST CDS_LIB pure_quanta
J 0
(-3900 3625);
DISPLAY INVISIBLE (-3900 3625);
FORCEPROP 1 LAST CDS_LMAN_SYM_OUTLINE -125,150,125,-150
J 0
(-3900 3625);
DISPLAY 0.468085 (-3900 3625);
PAINT GREEN (-3900 3625);
DISPLAY INVISIBLE (-3900 3625);
FORCEPROP 1 LAST NEEDS_NO_SIZE TRUE
J 0
(-3900 3591);
DISPLAY 0.723404 (-3900 3591);
PAINT GREEN (-3900 3591);
DISPLAY INVISIBLE (-3900 3591);
FORCEPROP 2 LAST PART_TYPE SMLF
J 0
(-3750 3452);
DISPLAY 1.021277 (-3750 3452);
DISPLAY INVISIBLE (-3750 3452);
FORCEPROP 1 LAST PATH I18
J 0
(-3900 3625);
DISPLAY 0.723404 (-3900 3625);
PAINT GREEN (-3900 3625);
DISPLAY INVISIBLE (-3900 3625);
FORCEPROP 1 LAST PART_NUMBER BAM34150008
J 0
(-3725 3527);
DISPLAY 0.489362 (-3725 3527);
PAINT SKYBLUE (-3725 3527);
DISPLAY INVISIBLE (-3725 3527);
FORCEADD UNIVERSAL_GND..1
(-3725 2175);
FORCEPROP 3 LASTPIN (-3725 2225) SIG_NAME GND\g
J 0
(-3715 2235);
DISPLAY 0.659574 (-3715 2235);
PAINT MONO (-3715 2235);
DISPLAY INVISIBLE (-3715 2235);
FORCEPROP 2 LAST CDS_LIB pure_quanta_power
J 0
(-3725 2175);
DISPLAY INVISIBLE (-3725 2175);
FORCEPROP 1 LAST HDL_POWER GND
J 1
(-3700 2100);
DISPLAY 0.872340 (-3700 2100);
PAINT GREEN (-3700 2100);
DISPLAY INVISIBLE (-3700 2100);
FORCEPROP 1 LAST PATH I19
J 0
(-3650 2175);
DISPLAY 0.872340 (-3650 2175);
PAINT AQUA (-3650 2175);
DISPLAY INVISIBLE (-3650 2175);
FORCEADD Q_RES..1
(-5375 3200);
FORCEPROP 1 LAST LOCATION R149
J 0
(-5425 3250);
DISPLAY 0.489362 (-5425 3250);
PAINT SKYBLUE (-5425 3250);
FORCEPROP 0 LAST $SEC 1
J 0
(-5425 3275);
DISPLAY 0.680851 (-5425 3275);
PAINT MONO (-5425 3275);
DISPLAY INVISIBLE (-5425 3275);
FORCEPROP 0 LAST CDS_SEC 1
J 0
(-5425 3275);
DISPLAY 1.021277 (-5425 3275);
DISPLAY INVISIBLE (-5425 3275);
FORCEPROP 1 LASTPIN (-5475 3200) $PN 1
J 0
(-5463 3212);
DISPLAY 0.489362 (-5463 3212);
PAINT MONO (-5463 3212);
FORCEPROP 1 LASTPIN (-5275 3200) $PN 2
J 0
(-5313 3212);
DISPLAY 0.489362 (-5313 3212);
PAINT MONO (-5313 3212);
FORCEPROP 1 LAST MATERIAL CHIP
J 0
(-5575 3350);
DISPLAY 0.489362 (-5575 3350);
PAINT SKYBLUE (-5575 3350);
FORCEPROP 1 LAST VALUE 0
J 2
(-5500 3250);
DISPLAY 0.489362 (-5500 3250);
PAINT SKYBLUE (-5500 3250);
FORCEPROP 1 LAST TOLERANCE 5%
J 0
(-5400 3350);
DISPLAY 0.489362 (-5400 3350);
PAINT SKYBLUE (-5400 3350);
FORCEPROP 1 LAST WATTAGE 1/16W
J 0
(-5300 3375);
DISPLAY 0.489362 (-5300 3375);
PAINT SKYBLUE (-5300 3375);
FORCEPROP 1 LAST PACK_TYPE 0402LF
J 0
(-5300 3350);
DISPLAY 0.489362 (-5300 3350);
PAINT SKYBLUE (-5300 3350);
FORCEPROP 2 LAST CDS_LIB pure_quanta
J 0
(-5375 3200);
DISPLAY INVISIBLE (-5375 3200);
FORCEPROP 1 LAST PATH I2
J 0
(-5425 3350);
DISPLAY 0.978723 (-5425 3350);
PAINT WHITE (-5425 3350);
DISPLAY INVISIBLE (-5425 3350);
FORCEPROP 1 LAST PART_NUMBER CS00002JB13
J 0
(-5575 3375);
DISPLAY 0.489362 (-5575 3375);
PAINT SKYBLUE (-5575 3375);
DISPLAY INVISIBLE (-5575 3375);
FORCEADD Q_RES..2
(-3725 2425);
FORCEPROP 1 LAST LOCATION PR4
J 0
(-3675 2525);
DISPLAY 0.489362 (-3675 2525);
PAINT SKYBLUE (-3675 2525);
FORCEPROP 2 LAST SEC 1
J 0
(-3675 2650);
DISPLAY 0.680851 (-3675 2650);
PAINT MONO (-3675 2650);
DISPLAY INVISIBLE (-3675 2650);
FORCEPROP 1 LASTPIN (-3725 2525) $PN 1
J 0
(-3720 2487);
DISPLAY 0.489362 (-3720 2487);
PAINT MONO (-3720 2487);
FORCEPROP 1 LASTPIN (-3725 2325) $PN 2
J 0
(-3720 2335);
DISPLAY 0.489362 (-3720 2335);
PAINT MONO (-3720 2335);
FORCEPROP 1 LAST PACK_TYPE 0402LF
J 0
(-3675 2225);
DISPLAY 0.489362 (-3675 2225);
PAINT SKYBLUE (-3675 2225);
FORCEPROP 1 LAST VALUE 10K
J 0
(-3675 2475);
DISPLAY 0.489362 (-3675 2475);
PAINT SKYBLUE (-3675 2475);
FORCEPROP 1 LAST TOLERANCE 1%
J 0
(-3675 2425);
DISPLAY 0.489362 (-3675 2425);
PAINT SKYBLUE (-3675 2425);
FORCEPROP 1 LAST WATTAGE 1/16W
J 0
(-3675 2375);
DISPLAY 0.489362 (-3675 2375);
PAINT SKYBLUE (-3675 2375);
FORCEPROP 1 LAST MATERIAL CHIP
J 0
(-3675 2325);
DISPLAY 0.489362 (-3675 2325);
PAINT SKYBLUE (-3675 2325);
FORCEPROP 2 LAST CDS_LIB pure_quanta
J 0
(-3725 2425);
DISPLAY INVISIBLE (-3725 2425);
FORCEPROP 2 LAST SEC_TYPE 0402LF
J 0
(-3675 2650);
DISPLAY 1.021277 (-3675 2650);
DISPLAY INVISIBLE (-3675 2650);
FORCEPROP 1 LAST PATH I20
J 0
(-3675 2600);
DISPLAY 0.978723 (-3675 2600);
PAINT WHITE (-3675 2600);
DISPLAY INVISIBLE (-3675 2600);
FORCEPROP 1 LAST PART_NUMBER CS31002FB08
J 0
(-3675 2275);
DISPLAY 0.489362 (-3675 2275);
PAINT SKYBLUE (-3675 2275);
DISPLAY INVISIBLE (-3675 2275);
FORCEADD UNIVERSAL_GND..1
(-3250 2175);
FORCEPROP 3 LASTPIN (-3250 2225) SIG_NAME GND\g
J 0
(-3240 2235);
DISPLAY 0.659574 (-3240 2235);
PAINT MONO (-3240 2235);
DISPLAY INVISIBLE (-3240 2235);
FORCEPROP 2 LAST CDS_LIB pure_quanta_power
J 0
(-3250 2175);
DISPLAY INVISIBLE (-3250 2175);
FORCEPROP 1 LAST HDL_POWER GND
J 1
(-3225 2100);
DISPLAY 0.872340 (-3225 2100);
PAINT GREEN (-3225 2100);
DISPLAY INVISIBLE (-3225 2100);
FORCEPROP 1 LAST PATH I21
J 0
(-3175 2175);
DISPLAY 0.872340 (-3175 2175);
PAINT AQUA (-3175 2175);
DISPLAY INVISIBLE (-3175 2175);
FORCEADD Q_CAP..1
(-3250 2425);
FORCEPROP 1 LAST LOCATION PC243
J 0
(-3200 2525);
DISPLAY 0.489362 (-3200 2525);
PAINT SKYBLUE (-3200 2525);
FORCEPROP 0 LAST $SEC 1
J 0
(-3200 2550);
DISPLAY 0.680851 (-3200 2550);
PAINT MONO (-3200 2550);
DISPLAY INVISIBLE (-3200 2550);
FORCEPROP 0 LAST CDS_SEC 1
J 0
(-3200 2550);
DISPLAY 1.021277 (-3200 2550);
DISPLAY INVISIBLE (-3200 2550);
FORCEPROP 1 LASTPIN (-3250 2525) $PN 1
J 0
(-3240 2505);
DISPLAY 0.489362 (-3240 2505);
PAINT MONO (-3240 2505);
FORCEPROP 1 LASTPIN (-3250 2325) $PN 2
J 0
(-3240 2305);
DISPLAY 0.489362 (-3240 2305);
PAINT MONO (-3240 2305);
FORCEPROP 1 LAST MATERIAL X7R
J 0
(-3200 2325);
DISPLAY 0.489362 (-3200 2325);
PAINT SKYBLUE (-3200 2325);
FORCEPROP 1 LAST PACK_TYPE 0402
J 0
(-3200 2225);
DISPLAY 0.489362 (-3200 2225);
PAINT SKYBLUE (-3200 2225);
FORCEPROP 1 LAST TOLERANCE 10%
J 0
(-3200 2375);
DISPLAY 0.489362 (-3200 2375);
PAINT SKYBLUE (-3200 2375);
FORCEPROP 1 LAST VOLTAGE 25V
J 0
(-3200 2425);
DISPLAY 0.489362 (-3200 2425);
PAINT SKYBLUE (-3200 2425);
FORCEPROP 1 LAST VALUE 0.1UF
J 0
(-3200 2475);
DISPLAY 0.489362 (-3200 2475);
PAINT SKYBLUE (-3200 2475);
FORCEPROP 2 LAST CDS_LIB pure_quanta
J 0
(-3250 2425);
DISPLAY INVISIBLE (-3250 2425);
FORCEPROP 1 LAST PATH I22
J 0
(-3200 2575);
DISPLAY 0.978723 (-3200 2575);
PAINT WHITE (-3200 2575);
DISPLAY INVISIBLE (-3200 2575);
FORCEPROP 1 LAST PART_NUMBER CH4104K1B00
J 0
(-3200 2275);
DISPLAY 0.489362 (-3200 2275);
PAINT SKYBLUE (-3200 2275);
DISPLAY INVISIBLE (-3200 2275);
FORCEADD Q_RES..1
(-3100 2775);
FORCEPROP 1 LAST LOCATION R8166
J 0
(-3150 2825);
DISPLAY 0.489362 (-3150 2825);
PAINT SKYBLUE (-3150 2825);
FORCEPROP 0 LAST $SEC 1
J 0
(-3150 2875);
DISPLAY 0.680851 (-3150 2875);
PAINT MONO (-3150 2875);
DISPLAY INVISIBLE (-3150 2875);
FORCEPROP 0 LAST CDS_SEC 1
J 0
(-3150 2875);
DISPLAY 1.021277 (-3150 2875);
DISPLAY INVISIBLE (-3150 2875);
FORCEPROP 1 LASTPIN (-3200 2775) $PN 1
J 0
(-3188 2787);
DISPLAY 0.489362 (-3188 2787);
PAINT MONO (-3188 2787);
FORCEPROP 1 LASTPIN (-3000 2775) $PN 2
J 0
(-3038 2787);
DISPLAY 0.489362 (-3038 2787);
PAINT MONO (-3038 2787);
FORCEPROP 1 LAST TOLERANCE 5%
J 0
(-2975 2800);
DISPLAY 0.489362 (-2975 2800);
PAINT SKYBLUE (-2975 2800);
FORCEPROP 1 LAST PACK_TYPE 0402LF
J 0
(-3000 2700);
DISPLAY 0.489362 (-3000 2700);
PAINT SKYBLUE (-3000 2700);
FORCEPROP 1 LAST WATTAGE 1/16W
J 0
(-3000 2725);
DISPLAY 0.489362 (-3000 2725);
PAINT SKYBLUE (-3000 2725);
FORCEPROP 1 LAST MATERIAL CHIP
J 0
(-3350 2700);
DISPLAY 0.489362 (-3350 2700);
PAINT SKYBLUE (-3350 2700);
FORCEPROP 1 LAST VALUE 33
J 2
(-3225 2800);
DISPLAY 0.489362 (-3225 2800);
PAINT SKYBLUE (-3225 2800);
FORCEPROP 2 LAST CDS_LIB pure_quanta
J 0
(-3100 2775);
DISPLAY INVISIBLE (-3100 2775);
FORCEPROP 1 LAST PATH I23
J 0
(-3150 2925);
DISPLAY 0.978723 (-3150 2925);
PAINT WHITE (-3150 2925);
DISPLAY INVISIBLE (-3150 2925);
FORCEPROP 1 LAST PART_NUMBER CS03302JB10
J 0
(-3350 2725);
DISPLAY 0.489362 (-3350 2725);
PAINT SKYBLUE (-3350 2725);
DISPLAY INVISIBLE (-3350 2725);
FORCEADD VCC_CORE..1
(-2975 2500);
FORCEPROP 3 LASTPIN (-2975 2450) SIG_NAME P12V_AUX\g
J 0
(-2965 2460);
DISPLAY 0.659574 (-2965 2460);
PAINT MONO (-2965 2460);
DISPLAY INVISIBLE (-2965 2460);
FORCEPROP 1 LAST HDL_POWER P12V_AUX
J 1
(-2975 2550);
DISPLAY 0.489362 (-2975 2550);
PAINT GREEN (-2975 2550);
FORCEPROP 2 LAST CDS_LIB pure_quanta_power
J 0
(-2975 2500);
DISPLAY INVISIBLE (-2975 2500);
FORCEPROP 1 LAST PATH I24
J 0
(-2925 2525);
DISPLAY 0.872340 (-2925 2525);
PAINT AQUA (-2925 2525);
DISPLAY INVISIBLE (-2925 2525);
FORCEADD UNIVERSAL_GND..1
(-3875 2950);
FORCEPROP 3 LASTPIN (-3875 3000) SIG_NAME GND\g
J 0
(-3865 3010);
DISPLAY 0.659574 (-3865 3010);
PAINT MONO (-3865 3010);
DISPLAY INVISIBLE (-3865 3010);
FORCEPROP 2 LAST CDS_LIB pure_quanta_power
J 0
(-3875 2950);
DISPLAY INVISIBLE (-3875 2950);
FORCEPROP 1 LAST HDL_POWER GND
J 1
(-3850 2875);
DISPLAY 0.872340 (-3850 2875);
PAINT GREEN (-3850 2875);
DISPLAY INVISIBLE (-3850 2875);
FORCEPROP 1 LAST PATH I25
J 0
(-3800 2950);
DISPLAY 0.872340 (-3800 2950);
PAINT AQUA (-3800 2950);
DISPLAY INVISIBLE (-3800 2950);
FORCEADD Q_RES..1
(-3100 3025);
FORCEPROP 1 LAST LOCATION R8165
J 0
(-3150 3075);
DISPLAY 0.489362 (-3150 3075);
PAINT SKYBLUE (-3150 3075);
FORCEPROP 0 LAST $SEC 1
J 0
(-3150 3125);
DISPLAY 0.680851 (-3150 3125);
PAINT MONO (-3150 3125);
DISPLAY INVISIBLE (-3150 3125);
FORCEPROP 0 LAST CDS_SEC 1
J 0
(-3150 3125);
DISPLAY 1.021277 (-3150 3125);
DISPLAY INVISIBLE (-3150 3125);
FORCEPROP 1 LASTPIN (-3200 3025) $PN 1
J 0
(-3188 3037);
DISPLAY 0.489362 (-3188 3037);
PAINT MONO (-3188 3037);
FORCEPROP 1 LASTPIN (-3000 3025) $PN 2
J 0
(-3038 3037);
DISPLAY 0.489362 (-3038 3037);
PAINT MONO (-3038 3037);
FORCEPROP 1 LAST WATTAGE 1/16W
J 0
(-3000 2975);
DISPLAY 0.489362 (-3000 2975);
PAINT SKYBLUE (-3000 2975);
FORCEPROP 1 LAST PACK_TYPE 0402LF
J 0
(-3000 2925);
DISPLAY 0.489362 (-3000 2925);
PAINT SKYBLUE (-3000 2925);
FORCEPROP 1 LAST VALUE 1K
J 2
(-3250 3050);
DISPLAY 0.489362 (-3250 3050);
PAINT SKYBLUE (-3250 3050);
FORCEPROP 1 LAST TOLERANCE 1%
J 0
(-3000 3050);
DISPLAY 0.489362 (-3000 3050);
PAINT SKYBLUE (-3000 3050);
FORCEPROP 1 LAST MATERIAL CHIP
J 0
(-3425 2925);
DISPLAY 0.489362 (-3425 2925);
PAINT SKYBLUE (-3425 2925);
FORCEPROP 2 LAST CDS_LIB pure_quanta
J 0
(-3100 3025);
DISPLAY INVISIBLE (-3100 3025);
FORCEPROP 1 LAST PATH I27
J 0
(-3150 3175);
DISPLAY 0.978723 (-3150 3175);
PAINT WHITE (-3150 3175);
DISPLAY INVISIBLE (-3150 3175);
FORCEPROP 1 LAST PART_NUMBER CS21002FB06
J 0
(-3425 2975);
DISPLAY 0.489362 (-3425 2975);
PAINT SKYBLUE (-3425 2975);
DISPLAY INVISIBLE (-3425 2975);
FORCEADD VCC_CORE..1
(-3375 3175);
FORCEPROP 3 LASTPIN (-3375 3125) SIG_NAME P3V3_AUX\g
J 0
(-3365 3135);
DISPLAY 0.659574 (-3365 3135);
PAINT MONO (-3365 3135);
DISPLAY INVISIBLE (-3365 3135);
FORCEPROP 1 LAST HDL_POWER P3V3_AUX
J 1
(-3375 3225);
DISPLAY 0.489362 (-3375 3225);
PAINT GREEN (-3375 3225);
FORCEPROP 2 LAST CDS_LIB pure_quanta_power
J 0
(-3375 3175);
DISPLAY INVISIBLE (-3375 3175);
FORCEPROP 1 LAST PATH I28
J 0
(-3325 3200);
DISPLAY 0.872340 (-3325 3200);
PAINT AQUA (-3325 3200);
DISPLAY INVISIBLE (-3325 3200);
FORCEADD VCC_CORE..1
(-3000 3575);
FORCEPROP 3 LASTPIN (-3000 3525) SIG_NAME PVDD18_S5_P1\g
J 0
(-2990 3535);
DISPLAY 0.659574 (-2990 3535);
PAINT MONO (-2990 3535);
DISPLAY INVISIBLE (-2990 3535);
FORCEPROP 1 LAST HDL_POWER PVDD18_S5_P1
J 1
(-3000 3625);
DISPLAY 0.489362 (-3000 3625);
PAINT GREEN (-3000 3625);
FORCEPROP 2 LAST CDS_LIB pure_quanta_power
J 0
(-3000 3575);
DISPLAY INVISIBLE (-3000 3575);
FORCEPROP 1 LAST PATH I29
J 0
(-2950 3600);
DISPLAY 0.872340 (-2950 3600);
PAINT AQUA (-2950 3600);
DISPLAY INVISIBLE (-2950 3600);
FORCEADD UNIVERSAL_GND..1
(-5300 6550);
FORCEPROP 3 LASTPIN (-5300 6600) SIG_NAME GND\g
J 0
(-5290 6610);
DISPLAY 0.659574 (-5290 6610);
PAINT MONO (-5290 6610);
DISPLAY INVISIBLE (-5290 6610);
FORCEPROP 2 LAST CDS_LIB pure_quanta_power
J 0
(-5300 6550);
DISPLAY INVISIBLE (-5300 6550);
FORCEPROP 1 LAST HDL_POWER GND
J 1
(-5275 6475);
DISPLAY 0.872340 (-5275 6475);
PAINT GREEN (-5275 6475);
DISPLAY INVISIBLE (-5275 6475);
FORCEPROP 1 LAST PATH I3
J 0
(-5225 6550);
DISPLAY 0.872340 (-5225 6550);
PAINT AQUA (-5225 6550);
DISPLAY INVISIBLE (-5225 6550);
FORCEADD VCC_CORE..1
(-4550 4075);
FORCEPROP 3 LASTPIN (-4550 4025) SIG_NAME P3V3_AUX\g
J 0
(-4540 4035);
DISPLAY 0.659574 (-4540 4035);
PAINT MONO (-4540 4035);
DISPLAY INVISIBLE (-4540 4035);
FORCEPROP 1 LAST HDL_POWER P3V3_AUX
J 1
(-4550 4125);
DISPLAY 0.489362 (-4550 4125);
PAINT GREEN (-4550 4125);
FORCEPROP 2 LAST CDS_LIB pure_quanta_power
J 0
(-4550 4075);
DISPLAY INVISIBLE (-4550 4075);
FORCEPROP 1 LAST PATH I30
J 0
(-4500 4100);
DISPLAY 0.872340 (-4500 4100);
PAINT AQUA (-4500 4100);
DISPLAY INVISIBLE (-4500 4100);
FORCEADD OFFPAGE..4
R 2
(-4625 4475);
FORCEPROP 2 LAST $XR0 54 
J 0
(-4906 4475);
DISPLAY 0.638298 (-4906 4475);
PAINT MONO (-4906 4475);
FORCEPROP 2 LAST $XR1 210 
J 0
(-5026 4475);
DISPLAY 0.638298 (-5026 4475);
PAINT MONO (-5026 4475);
FORCEPROP 2 LAST CDS_LIB standard
J 0
(-4625 4475);
DISPLAY INVISIBLE (-4625 4475);
FORCEPROP 1 LAST OFFPAGE TRUE
J 2
(-4950 4350);
DISPLAY 0.872340 (-4950 4350);
PAINT GREEN (-4950 4350);
DISPLAY INVISIBLE (-4950 4350);
FORCEPROP 1 LAST COMMENT_BODY TRUE
J 2
(-4600 4375);
DISPLAY 0.872340 (-4600 4375);
PAINT GREEN (-4600 4375);
DISPLAY INVISIBLE (-4600 4375);
FORCEPROP 2 LAST PATH I31
J 0
(-4900 4525);
DISPLAY 0.680851 (-4900 4525);
DISPLAY INVISIBLE (-4900 4525);
FORCEADD OFFPAGE..4
R 2
(-4625 4725);
FORCEPROP 2 LAST $XR0 54 
J 0
(-4906 4725);
DISPLAY 0.638298 (-4906 4725);
PAINT MONO (-4906 4725);
FORCEPROP 2 LAST CDS_LIB standard
J 0
(-4625 4725);
DISPLAY INVISIBLE (-4625 4725);
FORCEPROP 1 LAST OFFPAGE TRUE
J 2
(-4950 4600);
DISPLAY 0.872340 (-4950 4600);
PAINT GREEN (-4950 4600);
DISPLAY INVISIBLE (-4950 4600);
FORCEPROP 1 LAST COMMENT_BODY TRUE
J 2
(-4600 4625);
DISPLAY 0.872340 (-4600 4625);
PAINT GREEN (-4600 4625);
DISPLAY INVISIBLE (-4600 4625);
FORCEPROP 2 LAST PATH I32
J 0
(-4900 4775);
DISPLAY 0.680851 (-4900 4775);
DISPLAY INVISIBLE (-4900 4775);
FORCEADD OFFPAGE..4
R 2
(-4625 5575);
FORCEPROP 2 LAST $XR0 54 
J 0
(-4906 5575);
DISPLAY 0.638298 (-4906 5575);
PAINT MONO (-4906 5575);
FORCEPROP 2 LAST $XR1 210 
J 0
(-5026 5575);
DISPLAY 0.638298 (-5026 5575);
PAINT MONO (-5026 5575);
FORCEPROP 2 LAST CDS_LIB standard
J 0
(-4625 5575);
DISPLAY INVISIBLE (-4625 5575);
FORCEPROP 1 LAST OFFPAGE TRUE
J 2
(-4950 5450);
DISPLAY 0.872340 (-4950 5450);
PAINT GREEN (-4950 5450);
DISPLAY INVISIBLE (-4950 5450);
FORCEPROP 1 LAST COMMENT_BODY TRUE
J 2
(-4600 5475);
DISPLAY 0.872340 (-4600 5475);
PAINT GREEN (-4600 5475);
DISPLAY INVISIBLE (-4600 5475);
FORCEPROP 2 LAST PATH I33
J 0
(-4900 5625);
DISPLAY 0.680851 (-4900 5625);
DISPLAY INVISIBLE (-4900 5625);
FORCEADD OFFPAGE..4
R 2
(-4625 5825);
FORCEPROP 2 LAST $XR0 54 
J 0
(-4906 5825);
DISPLAY 0.638298 (-4906 5825);
PAINT MONO (-4906 5825);
FORCEPROP 2 LAST CDS_LIB standard
J 2
(-4625 5825);
DISPLAY INVISIBLE (-4625 5825);
FORCEPROP 1 LAST OFFPAGE TRUE
J 2
(-4950 5700);
DISPLAY 0.872340 (-4950 5700);
PAINT GREEN (-4950 5700);
DISPLAY INVISIBLE (-4950 5700);
FORCEPROP 1 LAST COMMENT_BODY TRUE
J 2
(-4600 5725);
DISPLAY 0.872340 (-4600 5725);
PAINT GREEN (-4600 5725);
DISPLAY INVISIBLE (-4600 5725);
FORCEPROP 2 LAST PATH I34
J 0
(-4900 5875);
DISPLAY 0.680851 (-4900 5875);
DISPLAY INVISIBLE (-4900 5875);
FORCEADD UNIVERSAL_GND..1
(-3875 4100);
FORCEPROP 3 LASTPIN (-3875 4150) SIG_NAME GND\g
J 0
(-3865 4160);
DISPLAY 0.659574 (-3865 4160);
PAINT MONO (-3865 4160);
DISPLAY INVISIBLE (-3865 4160);
FORCEPROP 2 LAST CDS_LIB pure_quanta_power
J 0
(-3875 4100);
DISPLAY INVISIBLE (-3875 4100);
FORCEPROP 1 LAST HDL_POWER GND
J 1
(-3850 4025);
DISPLAY 0.872340 (-3850 4025);
PAINT GREEN (-3850 4025);
DISPLAY INVISIBLE (-3850 4025);
FORCEPROP 1 LAST PATH I35
J 0
(-3800 4100);
DISPLAY 0.872340 (-3800 4100);
PAINT AQUA (-3800 4100);
DISPLAY INVISIBLE (-3800 4100);
FORCEADD Q_RES..2
(-3875 4300);
FORCEPROP 1 LAST LOCATION PR164
J 0
(-3825 4425);
DISPLAY 0.489362 (-3825 4425);
PAINT SKYBLUE (-3825 4425);
FORCEPROP 0 LAST $SEC 1
J 0
(-3825 4475);
DISPLAY 0.680851 (-3825 4475);
PAINT MONO (-3825 4475);
DISPLAY INVISIBLE (-3825 4475);
FORCEPROP 0 LAST CDS_SEC 1
J 0
(-3825 4475);
DISPLAY 1.021277 (-3825 4475);
DISPLAY INVISIBLE (-3825 4475);
FORCEPROP 1 LASTPIN (-3875 4400) $PN 1
J 0
(-3870 4362);
DISPLAY 0.489362 (-3870 4362);
PAINT MONO (-3870 4362);
FORCEPROP 1 LASTPIN (-3875 4200) $PN 2
J 0
(-3870 4210);
DISPLAY 0.489362 (-3870 4210);
PAINT MONO (-3870 4210);
FORCEPROP 1 LAST WATTAGE 1/16W
J 0
(-3825 4275);
DISPLAY 0.489362 (-3825 4275);
PAINT SKYBLUE (-3825 4275);
FORCEPROP 1 LAST MATERIAL CHIP
J 0
(-3825 4225);
DISPLAY 0.489362 (-3825 4225);
PAINT SKYBLUE (-3825 4225);
FORCEPROP 1 LAST PACK_TYPE 0402LF
J 0
(-3825 4125);
DISPLAY 0.489362 (-3825 4125);
PAINT SKYBLUE (-3825 4125);
FORCEPROP 1 LAST TOLERANCE 1%
J 0
(-3825 4325);
DISPLAY 0.489362 (-3825 4325);
PAINT SKYBLUE (-3825 4325);
FORCEPROP 1 LAST VALUE 49.9
J 0
(-3825 4375);
DISPLAY 0.489362 (-3825 4375);
PAINT SKYBLUE (-3825 4375);
FORCEPROP 2 LAST CDS_LIB pure_quanta
J 0
(-3875 4300);
DISPLAY INVISIBLE (-3875 4300);
FORCEPROP 1 LAST PATH I36
J 0
(-3825 4475);
DISPLAY 0.978723 (-3825 4475);
PAINT WHITE (-3825 4475);
DISPLAY INVISIBLE (-3825 4475);
FORCEPROP 1 LAST PART_NUMBER CS04992FB07
J 0
(-3825 4175);
DISPLAY 0.489362 (-3825 4175);
PAINT SKYBLUE (-3825 4175);
DISPLAY INVISIBLE (-3825 4175);
FORCEADD OFFPAGE..1
(-3500 4025);
FORCEPROP 2 LAST $XR0 78 
J 0
(-3721 4025);
DISPLAY 0.638298 (-3721 4025);
PAINT MONO (-3721 4025);
FORCEPROP 2 LAST CDS_LIB standard
J 0
(-3500 4025);
DISPLAY INVISIBLE (-3500 4025);
FORCEPROP 1 LAST OFFPAGE TRUE
J 0
(-3175 3900);
DISPLAY 0.872340 (-3175 3900);
PAINT GREEN (-3175 3900);
DISPLAY INVISIBLE (-3175 3900);
FORCEPROP 1 LAST COMMENT_BODY TRUE
J 0
(-3375 3925);
DISPLAY 0.872340 (-3375 3925);
PAINT GREEN (-3375 3925);
DISPLAY INVISIBLE (-3375 3925);
FORCEPROP 2 LAST PATH I37
J 0
(-3700 4075);
DISPLAY 0.680851 (-3700 4075);
DISPLAY INVISIBLE (-3700 4075);
FORCEADD OFFPAGE..5
(-3500 3875);
FORCEPROP 2 LAST $XR0 82 
J 0
(-3724 3875);
DISPLAY 0.638298 (-3724 3875);
PAINT MONO (-3724 3875);
FORCEPROP 2 LAST CDS_LIB standard
J 0
(-3500 3875);
DISPLAY INVISIBLE (-3500 3875);
FORCEPROP 1 LAST OFFPAGE TRUE
J 0
(-3175 3750);
DISPLAY 0.872340 (-3175 3750);
PAINT GREEN (-3175 3750);
DISPLAY INVISIBLE (-3175 3750);
FORCEPROP 1 LAST COMMENT_BODY TRUE
J 0
(-3400 3800);
DISPLAY 0.872340 (-3400 3800);
PAINT GREEN (-3400 3800);
DISPLAY INVISIBLE (-3400 3800);
FORCEPROP 2 LAST PATH I38
J 0
(-3750 3925);
DISPLAY 0.680851 (-3750 3925);
DISPLAY INVISIBLE (-3750 3925);
FORCEADD Q_RES..2
(-3875 4900);
FORCEPROP 1 LAST LOCATION PR163
J 0
(-3825 5025);
DISPLAY 0.489362 (-3825 5025);
PAINT SKYBLUE (-3825 5025);
FORCEPROP 0 LAST $SEC 1
J 0
(-3825 5075);
DISPLAY 0.680851 (-3825 5075);
PAINT MONO (-3825 5075);
DISPLAY INVISIBLE (-3825 5075);
FORCEPROP 0 LAST CDS_SEC 1
J 0
(-3825 5075);
DISPLAY 1.021277 (-3825 5075);
DISPLAY INVISIBLE (-3825 5075);
FORCEPROP 1 LASTPIN (-3875 5000) $PN 1
J 0
(-3870 4962);
DISPLAY 0.489362 (-3870 4962);
PAINT MONO (-3870 4962);
FORCEPROP 1 LASTPIN (-3875 4800) $PN 2
J 0
(-3870 4810);
DISPLAY 0.489362 (-3870 4810);
PAINT MONO (-3870 4810);
FORCEPROP 1 LAST TOLERANCE 1%
J 0
(-3825 4925);
DISPLAY 0.489362 (-3825 4925);
PAINT SKYBLUE (-3825 4925);
FORCEPROP 1 LAST VALUE 49.9
J 0
(-3825 4975);
DISPLAY 0.489362 (-3825 4975);
PAINT SKYBLUE (-3825 4975);
FORCEPROP 1 LAST PACK_TYPE 0402LF
J 0
(-3825 4725);
DISPLAY 0.489362 (-3825 4725);
PAINT SKYBLUE (-3825 4725);
FORCEPROP 1 LAST MATERIAL CHIP
J 0
(-3825 4825);
DISPLAY 0.489362 (-3825 4825);
PAINT SKYBLUE (-3825 4825);
FORCEPROP 1 LAST WATTAGE 1/16W
J 0
(-3825 4875);
DISPLAY 0.489362 (-3825 4875);
PAINT SKYBLUE (-3825 4875);
FORCEPROP 2 LAST CDS_LIB pure_quanta
J 0
(-3875 4900);
DISPLAY INVISIBLE (-3875 4900);
FORCEPROP 1 LAST PATH I39
J 0
(-3825 5075);
DISPLAY 0.978723 (-3825 5075);
PAINT WHITE (-3825 5075);
DISPLAY INVISIBLE (-3825 5075);
FORCEPROP 1 LAST PART_NUMBER CS04992FB07
J 0
(-3825 4775);
DISPLAY 0.489362 (-3825 4775);
PAINT SKYBLUE (-3825 4775);
DISPLAY INVISIBLE (-3825 4775);
FORCEADD Q_RES..2
(-5300 6800);
FORCEPROP 1 LAST LOCATION PR150
J 0
(-5255 6925);
DISPLAY 0.489362 (-5255 6925);
PAINT SKYBLUE (-5255 6925);
FORCEPROP 0 LAST $SEC 1
J 0
(-5250 6950);
DISPLAY 0.680851 (-5250 6950);
PAINT MONO (-5250 6950);
DISPLAY INVISIBLE (-5250 6950);
FORCEPROP 0 LAST CDS_SEC 1
J 0
(-5250 6950);
DISPLAY 1.021277 (-5250 6950);
DISPLAY INVISIBLE (-5250 6950);
FORCEPROP 1 LASTPIN (-5300 6900) $PN 1
J 0
(-5295 6862);
DISPLAY 0.489362 (-5295 6862);
PAINT MONO (-5295 6862);
FORCEPROP 1 LASTPIN (-5300 6700) $PN 2
J 0
(-5295 6710);
DISPLAY 0.489362 (-5295 6710);
PAINT MONO (-5295 6710);
FORCEPROP 1 LAST PACK_TYPE 0402LF
J 0
(-5250 6675);
DISPLAY 0.489362 (-5250 6675);
PAINT SKYBLUE (-5250 6675);
FORCEPROP 1 LAST MATERIAL CHIP
J 0
(-5250 6725);
DISPLAY 0.489362 (-5250 6725);
PAINT SKYBLUE (-5250 6725);
FORCEPROP 1 LAST WATTAGE 1/16W
J 0
(-5250 6775);
DISPLAY 0.489362 (-5250 6775);
PAINT SKYBLUE (-5250 6775);
FORCEPROP 1 LAST VALUE 0
J 0
(-5250 6875);
DISPLAY 0.489362 (-5250 6875);
PAINT SKYBLUE (-5250 6875);
FORCEPROP 1 LAST TOLERANCE 5%
J 0
(-5250 6825);
DISPLAY 0.489362 (-5250 6825);
PAINT SKYBLUE (-5250 6825);
FORCEPROP 2 LAST CDS_LIB pure_quanta
J 0
(-5300 6800);
DISPLAY INVISIBLE (-5300 6800);
FORCEPROP 1 LAST PATH I4
J 0
(-5250 6975);
DISPLAY 0.978723 (-5250 6975);
PAINT WHITE (-5250 6975);
DISPLAY INVISIBLE (-5250 6975);
FORCEPROP 1 LAST PART_NUMBER CS00002JB13
J 0
(-5300 6600);
DISPLAY 0.489362 (-5300 6600);
PAINT SKYBLUE (-5300 6600);
DISPLAY INVISIBLE (-5300 6600);
FORCEADD VCC_CORE..1
(-3300 4300);
FORCEPROP 3 LASTPIN (-3300 4250) SIG_NAME PVDD18_S5_P1\g
J 0
(-3290 4260);
DISPLAY 0.659574 (-3290 4260);
PAINT MONO (-3290 4260);
DISPLAY INVISIBLE (-3290 4260);
FORCEPROP 1 LAST HDL_POWER PVDD18_S5_P1
J 1
(-3300 4350);
DISPLAY 0.489362 (-3300 4350);
PAINT GREEN (-3300 4350);
FORCEPROP 2 LAST CDS_LIB pure_quanta_power
J 0
(-3300 4300);
DISPLAY INVISIBLE (-3300 4300);
FORCEPROP 1 LAST PATH I40
J 0
(-3250 4325);
DISPLAY 0.872340 (-3250 4325);
PAINT AQUA (-3250 4325);
DISPLAY INVISIBLE (-3250 4325);
FORCEADD Q_RES..1
(-2850 4175);
FORCEPROP 1 LAST LOCATION R8184
J 0
(-3225 4200);
DISPLAY 0.489362 (-3225 4200);
PAINT SKYBLUE (-3225 4200);
FORCEPROP 0 LAST $SEC 1
J 0
(-3100 4275);
DISPLAY 0.680851 (-3100 4275);
PAINT MONO (-3100 4275);
DISPLAY INVISIBLE (-3100 4275);
FORCEPROP 0 LAST CDS_SEC 1
J 0
(-3100 4275);
DISPLAY 1.021277 (-3100 4275);
DISPLAY INVISIBLE (-3100 4275);
FORCEPROP 1 LASTPIN (-2950 4175) $PN 1
J 0
(-2938 4187);
DISPLAY 0.489362 (-2938 4187);
PAINT MONO (-2938 4187);
FORCEPROP 1 LASTPIN (-2750 4175) $PN 2
J 0
(-2788 4187);
DISPLAY 0.489362 (-2788 4187);
PAINT MONO (-2788 4187);
FORCEPROP 1 LAST TOLERANCE 1%
J 0
(-3025 4200);
DISPLAY 0.489362 (-3025 4200);
PAINT SKYBLUE (-3025 4200);
FORCEPROP 1 LAST VALUE 1K
J 2
(-3050 4200);
DISPLAY 0.489362 (-3050 4200);
PAINT SKYBLUE (-3050 4200);
FORCEPROP 1 LAST WATTAGE 1/16W
J 2
(-2575 4200);
DISPLAY 0.489362 (-2575 4200);
PAINT SKYBLUE (-2575 4200);
FORCEPROP 1 LAST MATERIAL CHIP
J 0
(-2800 4200);
DISPLAY 0.489362 (-2800 4200);
PAINT SKYBLUE (-2800 4200);
FORCEPROP 1 LAST PACK_TYPE 0402LF
J 0
(-2950 4200);
DISPLAY 0.489362 (-2950 4200);
PAINT SKYBLUE (-2950 4200);
FORCEPROP 2 LAST CDS_LIB pure_quanta
J 0
(-2850 4175);
DISPLAY INVISIBLE (-2850 4175);
FORCEPROP 1 LAST PATH I41
J 0
(-2900 4325);
DISPLAY 0.978723 (-2900 4325);
PAINT WHITE (-2900 4325);
DISPLAY INVISIBLE (-2900 4325);
FORCEPROP 1 LAST PART_NUMBER CS21002FB06
J 0
(-3100 4250);
DISPLAY 0.489362 (-3100 4250);
PAINT SKYBLUE (-3100 4250);
DISPLAY INVISIBLE (-3100 4250);
FORCEADD Q_RES..1
(-2825 4025);
FORCEPROP 1 LAST LOCATION R8182
J 0
(-2875 4075);
DISPLAY 0.489362 (-2875 4075);
PAINT SKYBLUE (-2875 4075);
FORCEPROP 0 LAST $SEC 1
J 0
(-2875 4100);
DISPLAY 0.680851 (-2875 4100);
PAINT MONO (-2875 4100);
DISPLAY INVISIBLE (-2875 4100);
FORCEPROP 0 LAST CDS_SEC 1
J 0
(-2875 4100);
DISPLAY 1.021277 (-2875 4100);
DISPLAY INVISIBLE (-2875 4100);
FORCEPROP 1 LASTPIN (-2925 4025) $PN 1
J 0
(-2913 4037);
DISPLAY 0.489362 (-2913 4037);
PAINT MONO (-2913 4037);
FORCEPROP 1 LASTPIN (-2725 4025) $PN 2
J 0
(-2763 4037);
DISPLAY 0.489362 (-2763 4037);
PAINT MONO (-2763 4037);
FORCEPROP 1 LAST MATERIAL CHIP
J 0
(-3150 3975);
DISPLAY 0.489362 (-3150 3975);
PAINT SKYBLUE (-3150 3975);
FORCEPROP 1 LAST WATTAGE 1/16W
J 2
(-2900 3975);
DISPLAY 0.489362 (-2900 3975);
PAINT SKYBLUE (-2900 3975);
FORCEPROP 1 LAST PACK_TYPE 0402LF
J 0
(-2650 3975);
DISPLAY 0.489362 (-2650 3975);
PAINT SKYBLUE (-2650 3975);
FORCEPROP 1 LAST TOLERANCE 1%
J 0
(-2725 3975);
DISPLAY 0.489362 (-2725 3975);
PAINT SKYBLUE (-2725 3975);
FORCEPROP 1 LAST VALUE 49.9
J 2
(-2775 3975);
DISPLAY 0.489362 (-2775 3975);
PAINT SKYBLUE (-2775 3975);
FORCEPROP 2 LAST CDS_LIB pure_quanta
J 0
(-2825 4025);
DISPLAY INVISIBLE (-2825 4025);
FORCEPROP 1 LAST PATH I42
J 0
(-2875 4175);
DISPLAY 0.978723 (-2875 4175);
PAINT WHITE (-2875 4175);
DISPLAY INVISIBLE (-2875 4175);
FORCEPROP 1 LAST PART_NUMBER CS04992FB07
J 0
(-3500 3975);
DISPLAY 0.489362 (-3500 3975);
PAINT SKYBLUE (-3500 3975);
DISPLAY INVISIBLE (-3500 3975);
FORCEADD Q_RES..1
(-2825 3875);
FORCEPROP 1 LAST LOCATION R8168
J 0
(-2875 3925);
DISPLAY 0.489362 (-2875 3925);
PAINT SKYBLUE (-2875 3925);
FORCEPROP 0 LAST $SEC 1
J 0
(-2875 3950);
DISPLAY 0.680851 (-2875 3950);
PAINT MONO (-2875 3950);
DISPLAY INVISIBLE (-2875 3950);
FORCEPROP 0 LAST CDS_SEC 1
J 0
(-2875 3950);
DISPLAY 1.021277 (-2875 3950);
DISPLAY INVISIBLE (-2875 3950);
FORCEPROP 1 LASTPIN (-2925 3875) $PN 1
J 0
(-2913 3887);
DISPLAY 0.489362 (-2913 3887);
PAINT MONO (-2913 3887);
FORCEPROP 1 LASTPIN (-2725 3875) $PN 2
J 0
(-2763 3887);
DISPLAY 0.489362 (-2763 3887);
PAINT MONO (-2763 3887);
FORCEPROP 1 LAST PACK_TYPE 0402LF
J 0
(-2725 3825);
DISPLAY 0.489362 (-2725 3825);
PAINT SKYBLUE (-2725 3825);
FORCEPROP 1 LAST MATERIAL CHIP
J 0
(-3150 3825);
DISPLAY 0.489362 (-3150 3825);
PAINT SKYBLUE (-3150 3825);
FORCEPROP 1 LAST TOLERANCE 5%
J 0
(-2800 3825);
DISPLAY 0.489362 (-2800 3825);
PAINT SKYBLUE (-2800 3825);
FORCEPROP 1 LAST VALUE 0
J 2
(-2825 3825);
DISPLAY 0.489362 (-2825 3825);
PAINT SKYBLUE (-2825 3825);
FORCEPROP 1 LAST WATTAGE 1/16W
J 2
(-2900 3825);
DISPLAY 0.489362 (-2900 3825);
PAINT SKYBLUE (-2900 3825);
FORCEPROP 2 LAST CDS_LIB pure_quanta
J 0
(-2825 3875);
DISPLAY INVISIBLE (-2825 3875);
FORCEPROP 1 LAST PATH I43
J 0
(-2875 4025);
DISPLAY 0.978723 (-2875 4025);
PAINT WHITE (-2875 4025);
DISPLAY INVISIBLE (-2875 4025);
FORCEPROP 1 LAST PART_NUMBER CS00002JB13
J 0
(-3500 3825);
DISPLAY 0.489362 (-3500 3825);
PAINT SKYBLUE (-3500 3825);
DISPLAY INVISIBLE (-3500 3825);
FORCEADD VCC_CORE..1
(-3875 5075);
FORCEPROP 3 LASTPIN (-3875 5025) SIG_NAME PVDDCR_SOC_P1\g
J 0
(-3865 5035);
DISPLAY 0.659574 (-3865 5035);
PAINT MONO (-3865 5035);
DISPLAY INVISIBLE (-3865 5035);
FORCEPROP 1 LAST HDL_POWER PVDDCR_SOC_P1
J 1
(-3875 5125);
DISPLAY 0.489362 (-3875 5125);
PAINT GREEN (-3875 5125);
FORCEPROP 2 LAST CDS_LIB pure_quanta_power
J 0
(-3875 5075);
DISPLAY INVISIBLE (-3875 5075);
FORCEPROP 1 LAST PATH I44
J 0
(-3825 5100);
DISPLAY 0.872340 (-3825 5100);
PAINT AQUA (-3825 5100);
DISPLAY INVISIBLE (-3825 5100);
FORCEADD Q_RES..2
(-3875 5400);
FORCEPROP 1 LAST LOCATION PR162
J 0
(-3825 5525);
DISPLAY 0.489362 (-3825 5525);
PAINT SKYBLUE (-3825 5525);
FORCEPROP 0 LAST $SEC 1
J 0
(-3825 5550);
DISPLAY 0.680851 (-3825 5550);
PAINT MONO (-3825 5550);
DISPLAY INVISIBLE (-3825 5550);
FORCEPROP 0 LAST CDS_SEC 1
J 0
(-3825 5550);
DISPLAY 1.021277 (-3825 5550);
DISPLAY INVISIBLE (-3825 5550);
FORCEPROP 1 LASTPIN (-3875 5500) $PN 1
J 0
(-3870 5462);
DISPLAY 0.489362 (-3870 5462);
PAINT MONO (-3870 5462);
FORCEPROP 1 LASTPIN (-3875 5300) $PN 2
J 0
(-3870 5310);
DISPLAY 0.489362 (-3870 5310);
PAINT MONO (-3870 5310);
FORCEPROP 1 LAST TOLERANCE 1%
J 0
(-3825 5425);
DISPLAY 0.489362 (-3825 5425);
PAINT SKYBLUE (-3825 5425);
FORCEPROP 1 LAST PACK_TYPE 0402LF
J 0
(-3825 5225);
DISPLAY 0.489362 (-3825 5225);
PAINT SKYBLUE (-3825 5225);
FORCEPROP 1 LAST VALUE 49.9
J 0
(-3825 5475);
DISPLAY 0.489362 (-3825 5475);
PAINT SKYBLUE (-3825 5475);
FORCEPROP 1 LAST MATERIAL CHIP
J 0
(-3825 5325);
DISPLAY 0.489362 (-3825 5325);
PAINT SKYBLUE (-3825 5325);
FORCEPROP 1 LAST WATTAGE 1/16W
J 0
(-3825 5375);
DISPLAY 0.489362 (-3825 5375);
PAINT SKYBLUE (-3825 5375);
FORCEPROP 2 LAST CDS_LIB pure_quanta
J 0
(-3875 5400);
DISPLAY INVISIBLE (-3875 5400);
FORCEPROP 1 LAST PATH I45
J 0
(-3825 5575);
DISPLAY 0.978723 (-3825 5575);
PAINT WHITE (-3825 5575);
DISPLAY INVISIBLE (-3825 5575);
FORCEPROP 1 LAST PART_NUMBER CS04992FB07
J 0
(-3825 5275);
DISPLAY 0.489362 (-3825 5275);
PAINT SKYBLUE (-3825 5275);
DISPLAY INVISIBLE (-3825 5275);
FORCEADD UNIVERSAL_GND..1
(-3875 5200);
FORCEPROP 3 LASTPIN (-3875 5250) SIG_NAME GND\g
J 0
(-3865 5260);
DISPLAY 0.659574 (-3865 5260);
PAINT MONO (-3865 5260);
DISPLAY INVISIBLE (-3865 5260);
FORCEPROP 2 LAST CDS_LIB pure_quanta_power
J 0
(-3875 5200);
DISPLAY INVISIBLE (-3875 5200);
FORCEPROP 1 LAST HDL_POWER GND
J 1
(-3850 5125);
DISPLAY 0.872340 (-3850 5125);
PAINT GREEN (-3850 5125);
DISPLAY INVISIBLE (-3850 5125);
FORCEPROP 1 LAST PATH I46
J 0
(-3800 5200);
DISPLAY 0.872340 (-3800 5200);
PAINT AQUA (-3800 5200);
DISPLAY INVISIBLE (-3800 5200);
FORCEADD Q_RES..1
(-2725 2425);
FORCEPROP 1 LAST LOCATION PR181
J 0
(-2750 2475);
DISPLAY 0.489362 (-2750 2475);
PAINT SKYBLUE (-2750 2475);
FORCEPROP 0 LAST $SEC 1
J 0
(-2775 2525);
DISPLAY 0.680851 (-2775 2525);
PAINT MONO (-2775 2525);
DISPLAY INVISIBLE (-2775 2525);
FORCEPROP 0 LAST CDS_SEC 1
J 0
(-2775 2525);
DISPLAY 1.021277 (-2775 2525);
DISPLAY INVISIBLE (-2775 2525);
FORCEPROP 1 LASTPIN (-2825 2425) $PN 1
J 0
(-2813 2437);
DISPLAY 0.489362 (-2813 2437);
PAINT MONO (-2813 2437);
FORCEPROP 1 LASTPIN (-2625 2425) $PN 2
J 0
(-2663 2437);
DISPLAY 0.489362 (-2663 2437);
PAINT MONO (-2663 2437);
FORCEPROP 1 LAST MATERIAL CHIP
J 0
(-2975 2350);
DISPLAY 0.489362 (-2975 2350);
PAINT SKYBLUE (-2975 2350);
FORCEPROP 1 LAST PACK_TYPE 0402LF
J 0
(-2625 2350);
DISPLAY 0.489362 (-2625 2350);
PAINT SKYBLUE (-2625 2350);
FORCEPROP 1 LAST VALUE 0
J 2
(-2850 2450);
DISPLAY 0.489362 (-2850 2450);
PAINT SKYBLUE (-2850 2450);
FORCEPROP 1 LAST TOLERANCE 5%
J 0
(-2600 2450);
DISPLAY 0.489362 (-2600 2450);
PAINT SKYBLUE (-2600 2450);
FORCEPROP 1 LAST WATTAGE 1/16W
J 0
(-2625 2375);
DISPLAY 0.489362 (-2625 2375);
PAINT SKYBLUE (-2625 2375);
FORCEPROP 2 LAST CDS_LIB pure_quanta
J 0
(-2725 2425);
DISPLAY INVISIBLE (-2725 2425);
FORCEPROP 1 LAST PATH I47
J 0
(-2775 2575);
DISPLAY 0.978723 (-2775 2575);
PAINT WHITE (-2775 2575);
DISPLAY INVISIBLE (-2775 2575);
FORCEPROP 1 LAST PART_NUMBER CS00002JB13
J 0
(-2975 2375);
DISPLAY 0.489362 (-2975 2375);
PAINT SKYBLUE (-2975 2375);
DISPLAY INVISIBLE (-2975 2375);
FORCEADD Q_RES..2
(-2400 2225);
FORCEPROP 1 LAST LOCATION PR602
J 0
(-2350 2350);
DISPLAY 0.489362 (-2350 2350);
PAINT SKYBLUE (-2350 2350);
FORCEPROP 0 LAST $SEC 1
J 0
(-2350 2375);
DISPLAY 0.680851 (-2350 2375);
PAINT MONO (-2350 2375);
DISPLAY INVISIBLE (-2350 2375);
FORCEPROP 0 LAST CDS_SEC 1
J 0
(-2350 2375);
DISPLAY 0.680851 (-2350 2375);
DISPLAY INVISIBLE (-2350 2375);
FORCEPROP 1 LASTPIN (-2400 2325) $PN 1
J 0
(-2395 2287);
DISPLAY 0.787234 (-2395 2287);
PAINT MONO (-2395 2287);
DISPLAY INVISIBLE (-2395 2287);
FORCEPROP 1 LASTPIN (-2400 2125) $PN 2
J 0
(-2395 2135);
DISPLAY 0.787234 (-2395 2135);
PAINT MONO (-2395 2135);
DISPLAY INVISIBLE (-2395 2135);
FORCEPROP 1 LAST PACK_TYPE 0402LF
J 0
(-2350 2050);
DISPLAY 0.489362 (-2350 2050);
PAINT SKYBLUE (-2350 2050);
FORCEPROP 1 LAST VALUE 4.99K
J 0
(-2350 2300);
DISPLAY 0.489362 (-2350 2300);
PAINT SKYBLUE (-2350 2300);
FORCEPROP 1 LAST TOLERANCE 1%
J 0
(-2350 2250);
DISPLAY 0.489362 (-2350 2250);
PAINT SKYBLUE (-2350 2250);
FORCEPROP 1 LAST MATERIAL EMPTY
J 0
(-2350 2150);
DISPLAY 0.489362 (-2350 2150);
PAINT RED (-2350 2150);
FORCEPROP 1 LAST WATTAGE 1/16W
J 0
(-2350 2200);
DISPLAY 0.489362 (-2350 2200);
PAINT SKYBLUE (-2350 2200);
FORCEPROP 2 LAST CDS_LIB pure_quanta
J 0
(-2400 2225);
DISPLAY INVISIBLE (-2400 2225);
FORCEPROP 1 LAST PATH I48
J 0
(-2350 2400);
DISPLAY 0.978723 (-2350 2400);
PAINT WHITE (-2350 2400);
DISPLAY INVISIBLE (-2350 2400);
FORCEPROP 1 LAST PART_NUMBER CS24992FB07
J 0
(-2350 2100);
DISPLAY 0.489362 (-2350 2100);
PAINT SKYBLUE (-2350 2100);
DISPLAY INVISIBLE (-2350 2100);
FORCEADD UNIVERSAL_GND..1
(-2400 2025);
FORCEPROP 3 LASTPIN (-2400 2075) SIG_NAME GND\g
J 0
(-2390 2085);
DISPLAY 0.659574 (-2390 2085);
PAINT MONO (-2390 2085);
DISPLAY INVISIBLE (-2390 2085);
FORCEPROP 2 LAST CDS_LIB pure_quanta_power
J 0
(-2400 2025);
DISPLAY INVISIBLE (-2400 2025);
FORCEPROP 1 LAST HDL_POWER GND
J 1
(-2375 1950);
DISPLAY 0.872340 (-2375 1950);
PAINT GREEN (-2375 1950);
DISPLAY INVISIBLE (-2375 1950);
FORCEPROP 1 LAST PATH I49
J 0
(-2325 2025);
DISPLAY 0.872340 (-2325 2025);
PAINT AQUA (-2325 2025);
DISPLAY INVISIBLE (-2325 2025);
FORCEADD UNIVERSAL_GND..1
(-5025 6550);
FORCEPROP 3 LASTPIN (-5025 6600) SIG_NAME GND\g
J 0
(-5015 6610);
DISPLAY 0.659574 (-5015 6610);
PAINT MONO (-5015 6610);
DISPLAY INVISIBLE (-5015 6610);
FORCEPROP 2 LAST CDS_LIB pure_quanta_power
J 0
(-5025 6550);
DISPLAY INVISIBLE (-5025 6550);
FORCEPROP 1 LAST HDL_POWER GND
J 1
(-5000 6475);
DISPLAY 0.872340 (-5000 6475);
PAINT GREEN (-5000 6475);
DISPLAY INVISIBLE (-5000 6475);
FORCEPROP 1 LAST PATH I5
J 0
(-4950 6550);
DISPLAY 0.872340 (-4950 6550);
PAINT AQUA (-4950 6550);
DISPLAY INVISIBLE (-4950 6550);
FORCEADD UNIVERSAL_GND..1
(-2075 2025);
FORCEPROP 3 LASTPIN (-2075 2075) SIG_NAME GND\g
J 0
(-2065 2085);
DISPLAY 0.659574 (-2065 2085);
PAINT MONO (-2065 2085);
DISPLAY INVISIBLE (-2065 2085);
FORCEPROP 2 LAST CDS_LIB pure_quanta_power
J 0
(-2075 2025);
DISPLAY INVISIBLE (-2075 2025);
FORCEPROP 1 LAST HDL_POWER GND
J 1
(-2050 1950);
DISPLAY 0.872340 (-2050 1950);
PAINT GREEN (-2050 1950);
DISPLAY INVISIBLE (-2050 1950);
FORCEPROP 1 LAST PATH I50
J 0
(-2000 2025);
DISPLAY 0.872340 (-2000 2025);
PAINT AQUA (-2000 2025);
DISPLAY INVISIBLE (-2000 2025);
FORCEADD Q_CAP..1
(-2075 2250);
FORCEPROP 1 LAST LOCATION PC6
J 0
(-2025 2350);
DISPLAY 0.489362 (-2025 2350);
PAINT SKYBLUE (-2025 2350);
FORCEPROP 2 LAST SEC 1
J 0
(-2025 2450);
DISPLAY 0.680851 (-2025 2450);
PAINT MONO (-2025 2450);
DISPLAY INVISIBLE (-2025 2450);
FORCEPROP 1 LASTPIN (-2075 2350) $PN 1
J 0
(-2065 2330);
DISPLAY 0.489362 (-2065 2330);
PAINT MONO (-2065 2330);
FORCEPROP 1 LASTPIN (-2075 2150) $PN 2
J 0
(-2065 2130);
DISPLAY 0.489362 (-2065 2130);
PAINT MONO (-2065 2130);
FORCEPROP 1 LAST MATERIAL X7R
J 0
(-2025 2150);
DISPLAY 0.489362 (-2025 2150);
PAINT SKYBLUE (-2025 2150);
FORCEPROP 1 LAST TOLERANCE 10%
J 0
(-2025 2200);
DISPLAY 0.489362 (-2025 2200);
PAINT SKYBLUE (-2025 2200);
FORCEPROP 1 LAST VALUE 0.1UF
J 0
(-2025 2300);
DISPLAY 0.489362 (-2025 2300);
PAINT SKYBLUE (-2025 2300);
FORCEPROP 1 LAST VOLTAGE 25V
J 0
(-2025 2250);
DISPLAY 0.489362 (-2025 2250);
PAINT SKYBLUE (-2025 2250);
FORCEPROP 1 LAST PACK_TYPE 0402
J 0
(-2025 2050);
DISPLAY 0.489362 (-2025 2050);
PAINT SKYBLUE (-2025 2050);
FORCEPROP 2 LAST CDS_LIB pure_quanta
J 0
(-2075 2250);
DISPLAY INVISIBLE (-2075 2250);
FORCEPROP 2 LAST SEC_TYPE 0402
J 0
(-2025 2450);
DISPLAY 1.021277 (-2025 2450);
DISPLAY INVISIBLE (-2025 2450);
FORCEPROP 1 LAST PATH I51
J 0
(-2025 2400);
DISPLAY 0.978723 (-2025 2400);
PAINT WHITE (-2025 2400);
DISPLAY INVISIBLE (-2025 2400);
FORCEPROP 1 LAST PART_NUMBER CH4104K1B00
J 0
(-2025 2100);
DISPLAY 0.489362 (-2025 2100);
PAINT SKYBLUE (-2025 2100);
DISPLAY INVISIBLE (-2025 2100);
FORCEADD Q_CAP..2
(-2425 3025);
FORCEPROP 1 LAST LOCATION C8246
J 1
(-2425 3075);
DISPLAY 0.489362 (-2425 3075);
PAINT SKYBLUE (-2425 3075);
FORCEPROP 0 LAST $SEC 1
J 0
(-2425 3175);
DISPLAY 0.680851 (-2425 3175);
PAINT MONO (-2425 3175);
DISPLAY INVISIBLE (-2425 3175);
FORCEPROP 0 LAST CDS_SEC 1
J 0
(-2425 3175);
DISPLAY 1.021277 (-2425 3175);
DISPLAY INVISIBLE (-2425 3175);
FORCEPROP 1 LASTPIN (-2525 3025) $PN 1
J 0
(-2535 3040);
DISPLAY 0.489362 (-2535 3040);
PAINT MONO (-2535 3040);
FORCEPROP 1 LASTPIN (-2325 3025) $PN 2
J 0
(-2340 3040);
DISPLAY 0.489362 (-2340 3040);
PAINT MONO (-2340 3040);
FORCEPROP 1 LAST MATERIAL EMPTY
J 0
(-2700 2900);
DISPLAY 0.489362 (-2700 2900);
PAINT RED (-2700 2900);
FORCEPROP 1 LAST VALUE 1000PF
J 2
(-2550 3075);
DISPLAY 0.489362 (-2550 3075);
PAINT SKYBLUE (-2550 3075);
FORCEPROP 1 LAST VOLTAGE 50V
J 0
(-2300 3075);
DISPLAY 0.489362 (-2300 3075);
PAINT SKYBLUE (-2300 3075);
FORCEPROP 1 LAST PACK_TYPE 0402
J 0
(-2300 2950);
DISPLAY 0.489362 (-2300 2950);
PAINT SKYBLUE (-2300 2950);
FORCEPROP 1 LAST TOLERANCE 5%
J 0
(-2300 2900);
DISPLAY 0.489362 (-2300 2900);
PAINT SKYBLUE (-2300 2900);
FORCEPROP 2 LAST CDS_LIB pure_quanta
J 0
(-2425 3025);
DISPLAY INVISIBLE (-2425 3025);
FORCEPROP 1 LAST PATH I52
J 0
(-2425 3225);
DISPLAY 0.978723 (-2425 3225);
PAINT WHITE (-2425 3225);
DISPLAY INVISIBLE (-2425 3225);
FORCEPROP 1 LAST PART_NUMBER TMP_QCH21006JB10
J 1
(-2575 2950);
DISPLAY 0.489362 (-2575 2950);
PAINT SKYBLUE (-2575 2950);
DISPLAY INVISIBLE (-2575 2950);
FORCEADD UNIVERSAL_GND..1
(-2100 2900);
FORCEPROP 3 LASTPIN (-2100 2950) SIG_NAME GND\g
J 0
(-2090 2960);
DISPLAY 0.659574 (-2090 2960);
PAINT MONO (-2090 2960);
DISPLAY INVISIBLE (-2090 2960);
FORCEPROP 2 LAST CDS_LIB pure_quanta_power
J 0
(-2100 2900);
DISPLAY INVISIBLE (-2100 2900);
FORCEPROP 1 LAST HDL_POWER GND
J 1
(-2075 2825);
DISPLAY 0.872340 (-2075 2825);
PAINT GREEN (-2075 2825);
DISPLAY INVISIBLE (-2075 2825);
FORCEPROP 1 LAST PATH I53
J 0
(-2025 2900);
DISPLAY 0.872340 (-2025 2900);
PAINT AQUA (-2025 2900);
DISPLAY INVISIBLE (-2025 2900);
FORCEADD Q_RES..1
(-2175 3750);
FORCEPROP 1 LAST LOCATION R8180
J 0
(-2250 3800);
DISPLAY 0.489362 (-2250 3800);
PAINT SKYBLUE (-2250 3800);
FORCEPROP 0 LAST $SEC 1
J 0
(-2425 3850);
DISPLAY 0.680851 (-2425 3850);
PAINT MONO (-2425 3850);
DISPLAY INVISIBLE (-2425 3850);
FORCEPROP 0 LAST CDS_SEC 1
J 0
(-2425 3850);
DISPLAY 1.021277 (-2425 3850);
DISPLAY INVISIBLE (-2425 3850);
FORCEPROP 1 LASTPIN (-2275 3750) $PN 1
J 0
(-2263 3762);
DISPLAY 0.489362 (-2263 3762);
PAINT MONO (-2263 3762);
FORCEPROP 1 LASTPIN (-2075 3750) $PN 2
J 0
(-2113 3762);
DISPLAY 0.489362 (-2113 3762);
PAINT MONO (-2113 3762);
FORCEPROP 1 LAST MATERIAL CHIP
J 0
(-2150 3800);
DISPLAY 0.489362 (-2150 3800);
PAINT SKYBLUE (-2150 3800);
FORCEPROP 1 LAST WATTAGE 1/16W
J 2
(-1925 3800);
DISPLAY 0.489362 (-1925 3800);
PAINT SKYBLUE (-1925 3800);
FORCEPROP 1 LAST TOLERANCE 1%
J 0
(-2050 3650);
DISPLAY 0.489362 (-2050 3650);
PAINT SKYBLUE (-2050 3650);
FORCEPROP 1 LAST PACK_TYPE 0402LF
J 0
(-2100 3700);
DISPLAY 0.489362 (-2100 3700);
PAINT SKYBLUE (-2100 3700);
FORCEPROP 1 LAST VALUE 1K
J 2
(-2300 3775);
DISPLAY 0.489362 (-2300 3775);
PAINT SKYBLUE (-2300 3775);
FORCEPROP 2 LAST CDS_LIB pure_quanta
J 0
(-2175 3750);
DISPLAY INVISIBLE (-2175 3750);
FORCEPROP 1 LAST PATH I54
J 0
(-2225 3900);
DISPLAY 0.978723 (-2225 3900);
PAINT WHITE (-2225 3900);
DISPLAY INVISIBLE (-2225 3900);
FORCEPROP 1 LAST PART_NUMBER CS21002FB06
J 0
(-2550 3700);
DISPLAY 0.489362 (-2550 3700);
PAINT SKYBLUE (-2550 3700);
DISPLAY INVISIBLE (-2550 3700);
FORCEADD UNIVERSAL_GND..1
R 1
(-2050 3500);
FORCEPROP 3 LASTPIN (-2100 3500) SIG_NAME GND\g
J 0
(-2090 3510);
DISPLAY 0.659574 (-2090 3510);
PAINT MONO (-2090 3510);
DISPLAY INVISIBLE (-2090 3510);
FORCEPROP 2 LAST CDS_LIB pure_quanta_power
J 0
(-2050 3500);
DISPLAY INVISIBLE (-2050 3500);
FORCEPROP 1 LAST HDL_POWER GND
R 1
J 1
(-1975 3525);
DISPLAY 0.872340 (-1975 3525);
PAINT GREEN (-1975 3525);
DISPLAY INVISIBLE (-1975 3525);
FORCEPROP 1 LAST PATH I55
R 1
J 0
(-2050 3575);
DISPLAY 0.872340 (-2050 3575);
PAINT AQUA (-2050 3575);
DISPLAY INVISIBLE (-2050 3575);
FORCEADD UNIVERSAL_GND..1
(-1875 2225);
FORCEPROP 3 LASTPIN (-1875 2275) SIG_NAME GND\g
J 0
(-1865 2285);
DISPLAY 0.659574 (-1865 2285);
PAINT MONO (-1865 2285);
DISPLAY INVISIBLE (-1865 2285);
FORCEPROP 2 LAST CDS_LIB pure_quanta_power
J 0
(-1875 2225);
DISPLAY INVISIBLE (-1875 2225);
FORCEPROP 1 LAST HDL_POWER GND
J 1
(-1850 2150);
DISPLAY 0.872340 (-1850 2150);
PAINT GREEN (-1850 2150);
DISPLAY INVISIBLE (-1850 2150);
FORCEPROP 1 LAST PATH I56
J 0
(-1800 2225);
DISPLAY 0.872340 (-1800 2225);
PAINT AQUA (-1800 2225);
DISPLAY INVISIBLE (-1800 2225);
FORCEADD Q_RES..1
(-2725 4725);
FORCEPROP 1 LAST LOCATION PR174
J 0
(-2775 4775);
DISPLAY 0.489362 (-2775 4775);
PAINT SKYBLUE (-2775 4775);
FORCEPROP 0 LAST $SEC 1
J 0
(-2775 4825);
DISPLAY 0.680851 (-2775 4825);
PAINT MONO (-2775 4825);
DISPLAY INVISIBLE (-2775 4825);
FORCEPROP 0 LAST CDS_SEC 1
J 0
(-2775 4825);
DISPLAY 1.021277 (-2775 4825);
DISPLAY INVISIBLE (-2775 4825);
FORCEPROP 1 LASTPIN (-2825 4725) $PN 1
J 0
(-2813 4737);
DISPLAY 0.489362 (-2813 4737);
PAINT MONO (-2813 4737);
FORCEPROP 1 LASTPIN (-2625 4725) $PN 2
J 0
(-2663 4737);
DISPLAY 0.489362 (-2663 4737);
PAINT MONO (-2663 4737);
FORCEPROP 1 LAST PACK_TYPE 0402LF
J 0
(-2625 4650);
DISPLAY 0.489362 (-2625 4650);
PAINT SKYBLUE (-2625 4650);
FORCEPROP 1 LAST VALUE 0
J 2
(-2850 4750);
DISPLAY 0.489362 (-2850 4750);
PAINT SKYBLUE (-2850 4750);
FORCEPROP 1 LAST TOLERANCE 5%
J 0
(-2600 4750);
DISPLAY 0.489362 (-2600 4750);
PAINT SKYBLUE (-2600 4750);
FORCEPROP 1 LAST WATTAGE 1/16W
J 0
(-2625 4675);
DISPLAY 0.489362 (-2625 4675);
PAINT SKYBLUE (-2625 4675);
FORCEPROP 1 LAST MATERIAL CHIP
J 0
(-3050 4650);
DISPLAY 0.489362 (-3050 4650);
PAINT SKYBLUE (-3050 4650);
FORCEPROP 2 LAST CDS_LIB pure_quanta
J 0
(-2725 4725);
DISPLAY INVISIBLE (-2725 4725);
FORCEPROP 1 LAST PATH I57
J 0
(-2775 4875);
DISPLAY 0.978723 (-2775 4875);
PAINT WHITE (-2775 4875);
DISPLAY INVISIBLE (-2775 4875);
FORCEPROP 1 LAST PART_NUMBER CS00002JB13
J 0
(-3050 4675);
DISPLAY 0.489362 (-3050 4675);
PAINT SKYBLUE (-3050 4675);
DISPLAY INVISIBLE (-3050 4675);
FORCEADD Q_CAP..1
(-2450 4600);
FORCEPROP 1 LAST LOCATION PC245
J 0
(-2400 4650);
DISPLAY 0.489362 (-2400 4650);
PAINT SKYBLUE (-2400 4650);
FORCEPROP 0 LAST $SEC 1
J 0
(-2400 4750);
DISPLAY 0.680851 (-2400 4750);
PAINT MONO (-2400 4750);
DISPLAY INVISIBLE (-2400 4750);
FORCEPROP 0 LAST CDS_SEC 1
J 0
(-2400 4750);
DISPLAY 1.021277 (-2400 4750);
DISPLAY INVISIBLE (-2400 4750);
FORCEPROP 1 LASTPIN (-2450 4700) $PN 1
J 0
(-2440 4680);
DISPLAY 0.489362 (-2440 4680);
PAINT MONO (-2440 4680);
FORCEPROP 1 LASTPIN (-2450 4500) $PN 2
J 0
(-2440 4480);
DISPLAY 0.489362 (-2440 4480);
PAINT MONO (-2440 4480);
FORCEPROP 1 LAST PACK_TYPE 0402
J 0
(-2400 4500);
DISPLAY 0.489362 (-2400 4500);
PAINT SKYBLUE (-2400 4500);
FORCEPROP 1 LAST MATERIAL X7R
J 0
(-2400 4550);
DISPLAY 0.489362 (-2400 4550);
PAINT SKYBLUE (-2400 4550);
FORCEPROP 1 LAST VOLTAGE 50V
J 0
(-2400 4600);
DISPLAY 0.489362 (-2400 4600);
PAINT SKYBLUE (-2400 4600);
FORCEPROP 1 LAST VALUE 3300PF
J 0
(-2400 4625);
DISPLAY 0.489362 (-2400 4625);
PAINT SKYBLUE (-2400 4625);
FORCEPROP 1 LAST TOLERANCE 10%
J 0
(-2400 4575);
DISPLAY 0.489362 (-2400 4575);
PAINT SKYBLUE (-2400 4575);
FORCEPROP 2 LAST CDS_LIB pure_quanta
J 0
(-2450 4600);
DISPLAY INVISIBLE (-2450 4600);
FORCEPROP 1 LAST PATH I58
J 0
(-2400 4750);
DISPLAY 0.978723 (-2400 4750);
PAINT WHITE (-2400 4750);
DISPLAY INVISIBLE (-2400 4750);
FORCEPROP 1 LAST PART_NUMBER TMP_QCH2336K1B12
J 0
(-2400 4525);
DISPLAY 0.489362 (-2400 4525);
PAINT SKYBLUE (-2400 4525);
DISPLAY INVISIBLE (-2400 4525);
FORCEADD Q_RES..1
(-2800 5825);
FORCEPROP 1 LAST LOCATION PR173
J 0
(-2850 5875);
DISPLAY 0.489362 (-2850 5875);
PAINT SKYBLUE (-2850 5875);
FORCEPROP 0 LAST $SEC 1
J 0
(-2850 5900);
DISPLAY 0.680851 (-2850 5900);
PAINT MONO (-2850 5900);
DISPLAY INVISIBLE (-2850 5900);
FORCEPROP 0 LAST CDS_SEC 1
J 0
(-2850 5900);
DISPLAY 1.021277 (-2850 5900);
DISPLAY INVISIBLE (-2850 5900);
FORCEPROP 1 LASTPIN (-2900 5825) $PN 1
J 0
(-2888 5837);
DISPLAY 0.489362 (-2888 5837);
PAINT MONO (-2888 5837);
FORCEPROP 1 LASTPIN (-2700 5825) $PN 2
J 0
(-2738 5837);
DISPLAY 0.489362 (-2738 5837);
PAINT MONO (-2738 5837);
FORCEPROP 1 LAST TOLERANCE 5%
J 0
(-2675 5850);
DISPLAY 0.489362 (-2675 5850);
PAINT SKYBLUE (-2675 5850);
FORCEPROP 1 LAST VALUE 0
J 2
(-2925 5850);
DISPLAY 0.489362 (-2925 5850);
PAINT SKYBLUE (-2925 5850);
FORCEPROP 1 LAST PACK_TYPE 0402LF
J 0
(-2700 5750);
DISPLAY 0.489362 (-2700 5750);
PAINT SKYBLUE (-2700 5750);
FORCEPROP 1 LAST MATERIAL CHIP
J 0
(-3125 5750);
DISPLAY 0.489362 (-3125 5750);
PAINT SKYBLUE (-3125 5750);
FORCEPROP 1 LAST WATTAGE 1/16W
J 0
(-2700 5775);
DISPLAY 0.489362 (-2700 5775);
PAINT SKYBLUE (-2700 5775);
FORCEPROP 2 LAST CDS_LIB pure_quanta
J 0
(-2800 5825);
DISPLAY INVISIBLE (-2800 5825);
FORCEPROP 1 LAST PATH I59
J 0
(-2850 5975);
DISPLAY 0.978723 (-2850 5975);
PAINT WHITE (-2850 5975);
DISPLAY INVISIBLE (-2850 5975);
FORCEPROP 1 LAST PART_NUMBER CS00002JB13
J 0
(-3125 5775);
DISPLAY 0.489362 (-3125 5775);
PAINT SKYBLUE (-3125 5775);
DISPLAY INVISIBLE (-3125 5775);
FORCEADD Q_RES..2
(-5025 6800);
FORCEPROP 1 LAST LOCATION R8153
J 0
(-4975 6925);
DISPLAY 0.489362 (-4975 6925);
PAINT SKYBLUE (-4975 6925);
FORCEPROP 0 LAST $SEC 1
J 0
(-4975 6950);
DISPLAY 0.680851 (-4975 6950);
PAINT MONO (-4975 6950);
DISPLAY INVISIBLE (-4975 6950);
FORCEPROP 0 LAST CDS_SEC 1
J 0
(-4975 6950);
DISPLAY 1.021277 (-4975 6950);
DISPLAY INVISIBLE (-4975 6950);
FORCEPROP 1 LASTPIN (-5025 6900) $PN 1
J 0
(-5020 6862);
DISPLAY 0.489362 (-5020 6862);
PAINT MONO (-5020 6862);
FORCEPROP 1 LASTPIN (-5025 6700) $PN 2
J 0
(-5020 6710);
DISPLAY 0.489362 (-5020 6710);
PAINT MONO (-5020 6710);
FORCEPROP 1 LAST WATTAGE 1/16W
J 0
(-4975 6775);
DISPLAY 0.489362 (-4975 6775);
PAINT SKYBLUE (-4975 6775);
FORCEPROP 1 LAST PACK_TYPE 0402LF
J 0
(-4975 6675);
DISPLAY 0.489362 (-4975 6675);
PAINT SKYBLUE (-4975 6675);
FORCEPROP 1 LAST TOLERANCE 1%
J 0
(-4975 6825);
DISPLAY 0.489362 (-4975 6825);
PAINT SKYBLUE (-4975 6825);
FORCEPROP 1 LAST VALUE 1K
J 0
(-4975 6875);
DISPLAY 0.489362 (-4975 6875);
PAINT SKYBLUE (-4975 6875);
FORCEPROP 1 LAST MATERIAL EMPTY
J 0
(-4975 6725);
DISPLAY 0.489362 (-4975 6725);
PAINT RED (-4975 6725);
FORCEPROP 2 LAST CDS_LIB pure_quanta
J 0
(-5025 6800);
DISPLAY INVISIBLE (-5025 6800);
FORCEPROP 1 LAST PATH I6
J 0
(-4975 6975);
DISPLAY 0.978723 (-4975 6975);
PAINT WHITE (-4975 6975);
DISPLAY INVISIBLE (-4975 6975);
FORCEPROP 1 LAST PART_NUMBER CS21002FB06
J 0
(-4985 6675);
DISPLAY 0.489362 (-4985 6675);
PAINT SKYBLUE (-4985 6675);
DISPLAY INVISIBLE (-4985 6675);
FORCEADD Q_CAP..1
(-2525 5700);
FORCEPROP 1 LAST LOCATION PC244
J 0
(-2475 5750);
DISPLAY 0.489362 (-2475 5750);
PAINT SKYBLUE (-2475 5750);
FORCEPROP 0 LAST $SEC 1
J 0
(-2475 5775);
DISPLAY 0.680851 (-2475 5775);
PAINT MONO (-2475 5775);
DISPLAY INVISIBLE (-2475 5775);
FORCEPROP 0 LAST CDS_SEC 1
J 0
(-2475 5775);
DISPLAY 1.021277 (-2475 5775);
DISPLAY INVISIBLE (-2475 5775);
FORCEPROP 1 LASTPIN (-2525 5800) $PN 1
J 0
(-2515 5780);
DISPLAY 0.489362 (-2515 5780);
PAINT MONO (-2515 5780);
FORCEPROP 1 LASTPIN (-2525 5600) $PN 2
J 0
(-2515 5580);
DISPLAY 0.489362 (-2515 5580);
PAINT MONO (-2515 5580);
FORCEPROP 1 LAST MATERIAL X7R
J 0
(-2475 5650);
DISPLAY 0.489362 (-2475 5650);
PAINT SKYBLUE (-2475 5650);
FORCEPROP 1 LAST VOLTAGE 50V
J 0
(-2475 5700);
DISPLAY 0.489362 (-2475 5700);
PAINT SKYBLUE (-2475 5700);
FORCEPROP 1 LAST VALUE 3300PF
J 0
(-2475 5725);
DISPLAY 0.489362 (-2475 5725);
PAINT SKYBLUE (-2475 5725);
FORCEPROP 1 LAST TOLERANCE 10%
J 0
(-2475 5675);
DISPLAY 0.489362 (-2475 5675);
PAINT SKYBLUE (-2475 5675);
FORCEPROP 1 LAST PACK_TYPE 0402
J 0
(-2475 5600);
DISPLAY 0.489362 (-2475 5600);
PAINT SKYBLUE (-2475 5600);
FORCEPROP 2 LAST CDS_LIB pure_quanta
J 0
(-2525 5700);
DISPLAY INVISIBLE (-2525 5700);
FORCEPROP 1 LAST PATH I60
J 0
(-2475 5850);
DISPLAY 0.978723 (-2475 5850);
PAINT WHITE (-2475 5850);
DISPLAY INVISIBLE (-2475 5850);
FORCEPROP 1 LAST PART_NUMBER TMP_QCH2336K1B12
J 0
(-2475 5625);
DISPLAY 0.489362 (-2475 5625);
PAINT SKYBLUE (-2475 5625);
DISPLAY INVISIBLE (-2475 5625);
FORCEADD UNIVERSAL_GND..1
(-4825 6550);
FORCEPROP 3 LASTPIN (-4825 6600) SIG_NAME GND\g
J 0
(-4815 6610);
DISPLAY 0.659574 (-4815 6610);
PAINT MONO (-4815 6610);
DISPLAY INVISIBLE (-4815 6610);
FORCEPROP 2 LAST CDS_LIB pure_quanta_power
J 0
(-4825 6550);
DISPLAY INVISIBLE (-4825 6550);
FORCEPROP 1 LAST HDL_POWER GND
J 1
(-4800 6475);
DISPLAY 0.872340 (-4800 6475);
PAINT GREEN (-4800 6475);
DISPLAY INVISIBLE (-4800 6475);
FORCEPROP 1 LAST PATH I61
J 0
(-4750 6550);
DISPLAY 0.872340 (-4750 6550);
PAINT AQUA (-4750 6550);
DISPLAY INVISIBLE (-4750 6550);
FORCEADD Q_CAP..1
(-4825 6800);
FORCEPROP 1 LAST LOCATION C295
J 0
(-4775 6900);
DISPLAY 0.489362 (-4775 6900);
PAINT SKYBLUE (-4775 6900);
FORCEPROP 0 LAST $SEC 1
J 0
(-4775 6925);
DISPLAY 0.680851 (-4775 6925);
PAINT MONO (-4775 6925);
DISPLAY INVISIBLE (-4775 6925);
FORCEPROP 0 LAST CDS_SEC 1
J 0
(-4775 6925);
DISPLAY 1.021277 (-4775 6925);
DISPLAY INVISIBLE (-4775 6925);
FORCEPROP 1 LASTPIN (-4825 6900) $PN 1
J 0
(-4815 6880);
DISPLAY 0.489362 (-4815 6880);
PAINT MONO (-4815 6880);
FORCEPROP 1 LASTPIN (-4825 6700) $PN 2
J 0
(-4815 6680);
DISPLAY 0.489362 (-4815 6680);
PAINT MONO (-4815 6680);
FORCEPROP 1 LAST PACK_TYPE 0402
J 0
(-4775 6600);
DISPLAY 0.489362 (-4775 6600);
PAINT SKYBLUE (-4775 6600);
FORCEPROP 1 LAST VALUE 10PF
J 0
(-4775 6850);
DISPLAY 0.489362 (-4775 6850);
PAINT SKYBLUE (-4775 6850);
FORCEPROP 1 LAST TOLERANCE 5%
J 0
(-4775 6750);
DISPLAY 0.489362 (-4775 6750);
PAINT SKYBLUE (-4775 6750);
FORCEPROP 1 LAST VOLTAGE 50V
J 0
(-4775 6800);
DISPLAY 0.489362 (-4775 6800);
PAINT SKYBLUE (-4775 6800);
FORCEPROP 1 LAST MATERIAL EMPTY
J 0
(-4775 6700);
DISPLAY 0.489362 (-4775 6700);
PAINT RED (-4775 6700);
FORCEPROP 2 LAST CDS_LIB pure_quanta
J 0
(-4825 6800);
DISPLAY INVISIBLE (-4825 6800);
FORCEPROP 1 LAST PATH I62
J 0
(-4775 6950);
DISPLAY 0.978723 (-4775 6950);
PAINT WHITE (-4775 6950);
DISPLAY INVISIBLE (-4775 6950);
FORCEPROP 1 LAST PART_NUMBER CH01006JB08
J 0
(-4775 6650);
DISPLAY 0.489362 (-4775 6650);
PAINT SKYBLUE (-4775 6650);
DISPLAY INVISIBLE (-4775 6650);
FORCEADD UNIVERSAL_GND..1
(-4600 6550);
FORCEPROP 3 LASTPIN (-4600 6600) SIG_NAME GND\g
J 0
(-4590 6610);
DISPLAY 0.659574 (-4590 6610);
PAINT MONO (-4590 6610);
DISPLAY INVISIBLE (-4590 6610);
FORCEPROP 2 LAST CDS_LIB pure_quanta_power
J 0
(-4600 6550);
DISPLAY INVISIBLE (-4600 6550);
FORCEPROP 1 LAST HDL_POWER GND
J 1
(-4575 6475);
DISPLAY 0.872340 (-4575 6475);
PAINT GREEN (-4575 6475);
DISPLAY INVISIBLE (-4575 6475);
FORCEPROP 1 LAST PATH I63
J 0
(-4525 6550);
DISPLAY 0.872340 (-4525 6550);
PAINT AQUA (-4525 6550);
DISPLAY INVISIBLE (-4525 6550);
FORCEADD Q_CAP..1
(-4600 6800);
FORCEPROP 1 LAST LOCATION C296
J 0
(-4550 6900);
DISPLAY 0.489362 (-4550 6900);
PAINT SKYBLUE (-4550 6900);
FORCEPROP 0 LAST $SEC 1
J 0
(-4550 6925);
DISPLAY 0.680851 (-4550 6925);
PAINT MONO (-4550 6925);
DISPLAY INVISIBLE (-4550 6925);
FORCEPROP 0 LAST CDS_SEC 1
J 0
(-4550 6925);
DISPLAY 1.021277 (-4550 6925);
DISPLAY INVISIBLE (-4550 6925);
FORCEPROP 1 LASTPIN (-4600 6900) $PN 1
J 0
(-4590 6880);
DISPLAY 0.489362 (-4590 6880);
PAINT MONO (-4590 6880);
FORCEPROP 1 LASTPIN (-4600 6700) $PN 2
J 0
(-4590 6680);
DISPLAY 0.489362 (-4590 6680);
PAINT MONO (-4590 6680);
FORCEPROP 1 LAST MATERIAL EMPTY
J 0
(-4550 6700);
DISPLAY 0.489362 (-4550 6700);
PAINT RED (-4550 6700);
FORCEPROP 1 LAST VALUE 10PF
J 0
(-4550 6850);
DISPLAY 0.489362 (-4550 6850);
PAINT SKYBLUE (-4550 6850);
FORCEPROP 1 LAST TOLERANCE 5%
J 0
(-4550 6750);
DISPLAY 0.489362 (-4550 6750);
PAINT SKYBLUE (-4550 6750);
FORCEPROP 1 LAST VOLTAGE 50V
J 0
(-4550 6800);
DISPLAY 0.489362 (-4550 6800);
PAINT SKYBLUE (-4550 6800);
FORCEPROP 1 LAST PACK_TYPE 0402
J 0
(-4550 6600);
DISPLAY 0.489362 (-4550 6600);
PAINT SKYBLUE (-4550 6600);
FORCEPROP 2 LAST CDS_LIB pure_quanta
J 0
(-4600 6800);
DISPLAY INVISIBLE (-4600 6800);
FORCEPROP 1 LAST PATH I64
J 0
(-4550 6950);
DISPLAY 0.978723 (-4550 6950);
PAINT WHITE (-4550 6950);
DISPLAY INVISIBLE (-4550 6950);
FORCEPROP 1 LAST PART_NUMBER CH01006JB08
J 0
(-4550 6650);
DISPLAY 0.489362 (-4550 6650);
PAINT SKYBLUE (-4550 6650);
DISPLAY INVISIBLE (-4550 6650);
FORCEADD UNIVERSAL_GND..1
(-4325 6550);
FORCEPROP 3 LASTPIN (-4325 6600) SIG_NAME GND\g
J 0
(-4315 6610);
DISPLAY 0.659574 (-4315 6610);
PAINT MONO (-4315 6610);
DISPLAY INVISIBLE (-4315 6610);
FORCEPROP 2 LAST CDS_LIB pure_quanta_power
J 0
(-4325 6550);
DISPLAY INVISIBLE (-4325 6550);
FORCEPROP 1 LAST HDL_POWER GND
J 1
(-4300 6475);
DISPLAY 0.872340 (-4300 6475);
PAINT GREEN (-4300 6475);
DISPLAY INVISIBLE (-4300 6475);
FORCEPROP 1 LAST PATH I65
J 0
(-4250 6550);
DISPLAY 0.872340 (-4250 6550);
PAINT AQUA (-4250 6550);
DISPLAY INVISIBLE (-4250 6550);
FORCEADD Q_CAP..1
(-4325 6800);
FORCEPROP 1 LAST LOCATION C297
J 0
(-4275 6900);
DISPLAY 0.489362 (-4275 6900);
PAINT SKYBLUE (-4275 6900);
FORCEPROP 0 LAST $SEC 1
J 0
(-4275 6925);
DISPLAY 0.680851 (-4275 6925);
PAINT MONO (-4275 6925);
DISPLAY INVISIBLE (-4275 6925);
FORCEPROP 0 LAST CDS_SEC 1
J 0
(-4275 6925);
DISPLAY 1.021277 (-4275 6925);
DISPLAY INVISIBLE (-4275 6925);
FORCEPROP 1 LASTPIN (-4325 6900) $PN 1
J 0
(-4315 6880);
DISPLAY 0.489362 (-4315 6880);
PAINT MONO (-4315 6880);
FORCEPROP 1 LASTPIN (-4325 6700) $PN 2
J 0
(-4315 6680);
DISPLAY 0.489362 (-4315 6680);
PAINT MONO (-4315 6680);
FORCEPROP 1 LAST VALUE 10PF
J 0
(-4275 6850);
DISPLAY 0.489362 (-4275 6850);
PAINT SKYBLUE (-4275 6850);
FORCEPROP 1 LAST MATERIAL EMPTY
J 0
(-4275 6700);
DISPLAY 0.489362 (-4275 6700);
PAINT RED (-4275 6700);
FORCEPROP 1 LAST TOLERANCE 5%
J 0
(-4275 6750);
DISPLAY 0.489362 (-4275 6750);
PAINT SKYBLUE (-4275 6750);
FORCEPROP 1 LAST VOLTAGE 50V
J 0
(-4275 6800);
DISPLAY 0.489362 (-4275 6800);
PAINT SKYBLUE (-4275 6800);
FORCEPROP 1 LAST PACK_TYPE 0402
J 0
(-4275 6600);
DISPLAY 0.489362 (-4275 6600);
PAINT SKYBLUE (-4275 6600);
FORCEPROP 2 LAST CDS_LIB pure_quanta
J 0
(-4325 6800);
DISPLAY INVISIBLE (-4325 6800);
FORCEPROP 1 LAST PATH I66
J 0
(-4275 6950);
DISPLAY 0.978723 (-4275 6950);
PAINT WHITE (-4275 6950);
DISPLAY INVISIBLE (-4275 6950);
FORCEPROP 1 LAST PART_NUMBER CH01006JB08
J 0
(-4275 6650);
DISPLAY 0.489362 (-4275 6650);
PAINT SKYBLUE (-4275 6650);
DISPLAY INVISIBLE (-4275 6650);
FORCEADD Q_RES..2
(-4775 7750);
FORCEPROP 1 LAST LOCATION R154
J 0
(-4725 7875);
DISPLAY 0.489362 (-4725 7875);
PAINT SKYBLUE (-4725 7875);
FORCEPROP 0 LAST $SEC 1
J 0
(-4725 7900);
DISPLAY 0.680851 (-4725 7900);
PAINT MONO (-4725 7900);
DISPLAY INVISIBLE (-4725 7900);
FORCEPROP 0 LAST CDS_SEC 1
J 0
(-4725 7900);
DISPLAY 1.021277 (-4725 7900);
DISPLAY INVISIBLE (-4725 7900);
FORCEPROP 1 LASTPIN (-4775 7850) $PN 1
J 0
(-4770 7812);
DISPLAY 0.489362 (-4770 7812);
PAINT MONO (-4770 7812);
FORCEPROP 1 LASTPIN (-4775 7650) $PN 2
J 0
(-4770 7660);
DISPLAY 0.489362 (-4770 7660);
PAINT MONO (-4770 7660);
FORCEPROP 1 LAST MATERIAL EMPTY
J 0
(-4725 7675);
DISPLAY 0.489362 (-4725 7675);
PAINT RED (-4725 7675);
FORCEPROP 1 LAST PACK_TYPE 0402LF
J 0
(-4725 7625);
DISPLAY 0.489362 (-4725 7625);
PAINT SKYBLUE (-4725 7625);
FORCEPROP 1 LAST WATTAGE 1/16W
J 0
(-4725 7725);
DISPLAY 0.489362 (-4725 7725);
PAINT SKYBLUE (-4725 7725);
FORCEPROP 1 LAST VALUE 1K
J 0
(-4725 7825);
DISPLAY 0.489362 (-4725 7825);
PAINT SKYBLUE (-4725 7825);
FORCEPROP 1 LAST TOLERANCE 1%
J 0
(-4725 7775);
DISPLAY 0.489362 (-4725 7775);
PAINT SKYBLUE (-4725 7775);
FORCEPROP 2 LAST CDS_LIB pure_quanta
J 0
(-4775 7750);
DISPLAY INVISIBLE (-4775 7750);
FORCEPROP 1 LAST PATH I67
J 0
(-4725 7925);
DISPLAY 0.978723 (-4725 7925);
PAINT WHITE (-4725 7925);
DISPLAY INVISIBLE (-4725 7925);
FORCEPROP 1 LAST PART_NUMBER CS21002FB06
J 0
(-4735 7625);
DISPLAY 0.489362 (-4735 7625);
PAINT SKYBLUE (-4735 7625);
DISPLAY INVISIBLE (-4735 7625);
FORCEADD Q_RES..2
(-4475 7750);
FORCEPROP 1 LAST LOCATION R8156
J 0
(-4425 7875);
DISPLAY 0.489362 (-4425 7875);
PAINT SKYBLUE (-4425 7875);
FORCEPROP 0 LAST $SEC 1
J 0
(-4425 7900);
DISPLAY 0.680851 (-4425 7900);
PAINT MONO (-4425 7900);
DISPLAY INVISIBLE (-4425 7900);
FORCEPROP 0 LAST CDS_SEC 1
J 0
(-4425 7900);
DISPLAY 1.021277 (-4425 7900);
DISPLAY INVISIBLE (-4425 7900);
FORCEPROP 1 LASTPIN (-4475 7850) $PN 1
J 0
(-4470 7812);
DISPLAY 0.489362 (-4470 7812);
PAINT MONO (-4470 7812);
FORCEPROP 1 LASTPIN (-4475 7650) $PN 2
J 0
(-4470 7660);
DISPLAY 0.489362 (-4470 7660);
PAINT MONO (-4470 7660);
FORCEPROP 1 LAST PACK_TYPE 0402LF
J 0
(-4425 7625);
DISPLAY 0.489362 (-4425 7625);
PAINT SKYBLUE (-4425 7625);
FORCEPROP 1 LAST WATTAGE 1/16W
J 0
(-4425 7725);
DISPLAY 0.489362 (-4425 7725);
PAINT SKYBLUE (-4425 7725);
FORCEPROP 1 LAST MATERIAL EMPTY
J 0
(-4425 7675);
DISPLAY 0.489362 (-4425 7675);
PAINT RED (-4425 7675);
FORCEPROP 1 LAST TOLERANCE 1%
J 0
(-4425 7775);
DISPLAY 0.489362 (-4425 7775);
PAINT SKYBLUE (-4425 7775);
FORCEPROP 1 LAST VALUE 1K
J 0
(-4425 7825);
DISPLAY 0.489362 (-4425 7825);
PAINT SKYBLUE (-4425 7825);
FORCEPROP 2 LAST CDS_LIB pure_quanta
J 0
(-4475 7750);
DISPLAY INVISIBLE (-4475 7750);
FORCEPROP 1 LAST PATH I68
J 0
(-4425 7925);
DISPLAY 0.978723 (-4425 7925);
PAINT WHITE (-4425 7925);
DISPLAY INVISIBLE (-4425 7925);
FORCEPROP 1 LAST PART_NUMBER CS21002FB06
J 0
(-4435 7625);
DISPLAY 0.489362 (-4435 7625);
PAINT SKYBLUE (-4435 7625);
DISPLAY INVISIBLE (-4435 7625);
FORCEADD Q_RES..2
(-4200 7750);
FORCEPROP 1 LAST LOCATION R8160
J 0
(-4150 7875);
DISPLAY 0.489362 (-4150 7875);
PAINT SKYBLUE (-4150 7875);
FORCEPROP 0 LAST $SEC 1
J 0
(-4150 7900);
DISPLAY 0.680851 (-4150 7900);
PAINT MONO (-4150 7900);
DISPLAY INVISIBLE (-4150 7900);
FORCEPROP 0 LAST CDS_SEC 1
J 0
(-4150 7900);
DISPLAY 1.021277 (-4150 7900);
DISPLAY INVISIBLE (-4150 7900);
FORCEPROP 1 LASTPIN (-4200 7850) $PN 1
J 0
(-4195 7812);
DISPLAY 0.489362 (-4195 7812);
PAINT MONO (-4195 7812);
FORCEPROP 1 LASTPIN (-4200 7650) $PN 2
J 0
(-4195 7660);
DISPLAY 0.489362 (-4195 7660);
PAINT MONO (-4195 7660);
FORCEPROP 1 LAST WATTAGE 1/16W
J 0
(-4150 7725);
DISPLAY 0.489362 (-4150 7725);
PAINT SKYBLUE (-4150 7725);
FORCEPROP 1 LAST MATERIAL EMPTY
J 0
(-4150 7675);
DISPLAY 0.489362 (-4150 7675);
PAINT RED (-4150 7675);
FORCEPROP 1 LAST TOLERANCE 1%
J 0
(-4150 7775);
DISPLAY 0.489362 (-4150 7775);
PAINT SKYBLUE (-4150 7775);
FORCEPROP 1 LAST VALUE 1K
J 0
(-4150 7825);
DISPLAY 0.489362 (-4150 7825);
PAINT SKYBLUE (-4150 7825);
FORCEPROP 1 LAST PACK_TYPE 0402LF
J 0
(-4150 7575);
DISPLAY 0.489362 (-4150 7575);
PAINT SKYBLUE (-4150 7575);
FORCEPROP 2 LAST CDS_LIB pure_quanta
J 0
(-4200 7750);
DISPLAY INVISIBLE (-4200 7750);
FORCEPROP 1 LAST PATH I69
J 0
(-4150 7925);
DISPLAY 0.978723 (-4150 7925);
PAINT WHITE (-4150 7925);
DISPLAY INVISIBLE (-4150 7925);
FORCEPROP 1 LAST PART_NUMBER CS21002FB06
J 0
(-4150 7625);
DISPLAY 0.489362 (-4150 7625);
PAINT SKYBLUE (-4150 7625);
DISPLAY INVISIBLE (-4150 7625);
FORCEADD OFFPAGE..2
R 2
(-5675 7125);
FORCEPROP 2 LAST $XR0 54 
J 0
(-5899 7125);
DISPLAY 0.638298 (-5899 7125);
PAINT MONO (-5899 7125);
FORCEPROP 2 LAST CDS_LIB standard
J 0
(-5675 7125);
DISPLAY INVISIBLE (-5675 7125);
FORCEPROP 1 LAST OFFPAGE TRUE
J 2
(-6000 7000);
DISPLAY 0.872340 (-6000 7000);
PAINT GREEN (-6000 7000);
DISPLAY INVISIBLE (-6000 7000);
FORCEPROP 1 LAST COMMENT_BODY TRUE
J 2
(-5630 7030);
DISPLAY 0.872340 (-5630 7030);
PAINT GREEN (-5630 7030);
DISPLAY INVISIBLE (-5630 7030);
FORCEPROP 2 LAST PATH I7
J 0
(-5875 7175);
DISPLAY 0.680851 (-5875 7175);
DISPLAY INVISIBLE (-5875 7175);
FORCEADD Q_RES..2
(-3875 6025);
FORCEPROP 1 LAST LOCATION PR161
J 0
(-3825 6150);
DISPLAY 0.489362 (-3825 6150);
PAINT SKYBLUE (-3825 6150);
FORCEPROP 0 LAST $SEC 1
J 0
(-3825 6175);
DISPLAY 0.680851 (-3825 6175);
PAINT MONO (-3825 6175);
DISPLAY INVISIBLE (-3825 6175);
FORCEPROP 0 LAST CDS_SEC 1
J 0
(-3825 6175);
DISPLAY 1.021277 (-3825 6175);
DISPLAY INVISIBLE (-3825 6175);
FORCEPROP 1 LASTPIN (-3875 6125) $PN 1
J 0
(-3870 6087);
DISPLAY 0.489362 (-3870 6087);
PAINT MONO (-3870 6087);
FORCEPROP 1 LASTPIN (-3875 5925) $PN 2
J 0
(-3870 5935);
DISPLAY 0.489362 (-3870 5935);
PAINT MONO (-3870 5935);
FORCEPROP 1 LAST VALUE 49.9
J 0
(-3825 6100);
DISPLAY 0.489362 (-3825 6100);
PAINT SKYBLUE (-3825 6100);
FORCEPROP 1 LAST WATTAGE 1/16W
J 0
(-3825 6000);
DISPLAY 0.489362 (-3825 6000);
PAINT SKYBLUE (-3825 6000);
FORCEPROP 1 LAST PACK_TYPE 0402LF
J 0
(-3825 5850);
DISPLAY 0.489362 (-3825 5850);
PAINT SKYBLUE (-3825 5850);
FORCEPROP 1 LAST TOLERANCE 1%
J 0
(-3825 6050);
DISPLAY 0.489362 (-3825 6050);
PAINT SKYBLUE (-3825 6050);
FORCEPROP 1 LAST MATERIAL CHIP
J 0
(-3825 5950);
DISPLAY 0.489362 (-3825 5950);
PAINT SKYBLUE (-3825 5950);
FORCEPROP 2 LAST CDS_LIB pure_quanta
J 0
(-3875 6025);
DISPLAY INVISIBLE (-3875 6025);
FORCEPROP 1 LAST PATH I70
J 0
(-3825 6200);
DISPLAY 0.978723 (-3825 6200);
PAINT WHITE (-3825 6200);
DISPLAY INVISIBLE (-3825 6200);
FORCEPROP 1 LAST PART_NUMBER CS04992FB07
J 0
(-3825 5900);
DISPLAY 0.489362 (-3825 5900);
PAINT SKYBLUE (-3825 5900);
DISPLAY INVISIBLE (-3825 5900);
FORCEADD VCC_CORE..1
(-3875 6225);
FORCEPROP 3 LASTPIN (-3875 6175) SIG_NAME PVDDCR_CPU0_P1\g
J 0
(-3865 6185);
DISPLAY 0.659574 (-3865 6185);
PAINT MONO (-3865 6185);
DISPLAY INVISIBLE (-3865 6185);
FORCEPROP 1 LAST HDL_POWER PVDDCR_CPU0_P1
J 1
(-3875 6275);
DISPLAY 0.489362 (-3875 6275);
PAINT GREEN (-3875 6275);
FORCEPROP 2 LAST CDS_LIB pure_quanta_power
J 0
(-3875 6225);
DISPLAY INVISIBLE (-3875 6225);
FORCEPROP 1 LAST PATH I71
J 0
(-3825 6250);
DISPLAY 0.872340 (-3825 6250);
PAINT AQUA (-3825 6250);
DISPLAY INVISIBLE (-3825 6250);
FORCEADD OFFPAGE..3
R 2
(-3525 6575);
FORCEPROP 2 LAST $XR0 151 
J 0
(-3805 6575);
DISPLAY 0.638298 (-3805 6575);
PAINT MONO (-3805 6575);
FORCEPROP 2 LAST CDS_LIB standard
J 0
(-3525 6575);
DISPLAY INVISIBLE (-3525 6575);
FORCEPROP 1 LAST OFFPAGE TRUE
J 2
(-3850 6450);
DISPLAY 0.872340 (-3850 6450);
PAINT GREEN (-3850 6450);
DISPLAY INVISIBLE (-3850 6450);
FORCEPROP 1 LAST COMMENT_BODY TRUE
J 2
(-3475 6475);
DISPLAY 0.872340 (-3475 6475);
PAINT GREEN (-3475 6475);
DISPLAY INVISIBLE (-3475 6475);
FORCEPROP 2 LAST PATH I72
J 0
(-3800 6625);
DISPLAY 0.680851 (-3800 6625);
DISPLAY INVISIBLE (-3800 6625);
FORCEADD OFFPAGE..2
R 2
(-3525 6425);
FORCEPROP 2 LAST $XR0 83 
J 0
(-3749 6425);
DISPLAY 0.638298 (-3749 6425);
PAINT MONO (-3749 6425);
FORCEPROP 2 LAST $XR1 82 
J 0
(-3839 6425);
DISPLAY 0.638298 (-3839 6425);
PAINT MONO (-3839 6425);
FORCEPROP 2 LAST CDS_LIB standard
J 0
(-3525 6425);
DISPLAY INVISIBLE (-3525 6425);
FORCEPROP 1 LAST OFFPAGE TRUE
J 2
(-3850 6300);
DISPLAY 0.872340 (-3850 6300);
PAINT GREEN (-3850 6300);
DISPLAY INVISIBLE (-3850 6300);
FORCEPROP 1 LAST COMMENT_BODY TRUE
J 2
(-3480 6330);
DISPLAY 0.872340 (-3480 6330);
PAINT GREEN (-3480 6330);
DISPLAY INVISIBLE (-3480 6330);
FORCEPROP 2 LAST PATH I73
J 0
(-3725 6475);
DISPLAY 0.680851 (-3725 6475);
DISPLAY INVISIBLE (-3725 6475);
FORCEADD OFFPAGE..4
R 2
(-3525 6725);
FORCEPROP 2 LAST $XR0 151 
J 0
(-3777 6725);
DISPLAY 0.638298 (-3777 6725);
PAINT MONO (-3777 6725);
FORCEPROP 2 LAST CDS_LIB standard
J 0
(-3525 6725);
DISPLAY INVISIBLE (-3525 6725);
FORCEPROP 1 LAST OFFPAGE TRUE
J 2
(-3850 6600);
DISPLAY 0.872340 (-3850 6600);
PAINT GREEN (-3850 6600);
DISPLAY INVISIBLE (-3850 6600);
FORCEPROP 1 LAST COMMENT_BODY TRUE
J 2
(-3500 6625);
DISPLAY 0.872340 (-3500 6625);
PAINT GREEN (-3500 6625);
DISPLAY INVISIBLE (-3500 6625);
FORCEPROP 2 LAST PATH I74
J 0
(-3775 6775);
DISPLAY 0.680851 (-3775 6775);
DISPLAY INVISIBLE (-3775 6775);
FORCEADD OFFPAGE..2
R 2
(-3400 7875);
FORCEPROP 2 LAST $XR0 81 
J 0
(-3624 7875);
DISPLAY 0.638298 (-3624 7875);
PAINT MONO (-3624 7875);
FORCEPROP 2 LAST CDS_LIB standard
J 2
(-3400 7875);
DISPLAY INVISIBLE (-3400 7875);
FORCEPROP 1 LAST OFFPAGE TRUE
J 2
(-3725 7750);
DISPLAY 0.872340 (-3725 7750);
PAINT GREEN (-3725 7750);
DISPLAY INVISIBLE (-3725 7750);
FORCEPROP 1 LAST COMMENT_BODY TRUE
J 2
(-3355 7780);
DISPLAY 0.872340 (-3355 7780);
PAINT GREEN (-3355 7780);
DISPLAY INVISIBLE (-3355 7780);
FORCEPROP 2 LAST PATH I75
J 0
(-3650 7925);
DISPLAY 0.680851 (-3650 7925);
DISPLAY INVISIBLE (-3650 7925);
FORCEADD OFFPAGE..4
R 2
(-3400 7725);
FORCEPROP 2 LAST $XR0 81 
J 0
(-3621 7725);
DISPLAY 0.638298 (-3621 7725);
PAINT MONO (-3621 7725);
FORCEPROP 2 LAST CDS_LIB standard
J 0
(-3400 7725);
DISPLAY INVISIBLE (-3400 7725);
FORCEPROP 1 LAST OFFPAGE TRUE
J 2
(-3725 7600);
DISPLAY 0.872340 (-3725 7600);
PAINT GREEN (-3725 7600);
DISPLAY INVISIBLE (-3725 7600);
FORCEPROP 1 LAST COMMENT_BODY TRUE
J 2
(-3375 7625);
DISPLAY 0.872340 (-3375 7625);
PAINT GREEN (-3375 7625);
DISPLAY INVISIBLE (-3375 7625);
FORCEPROP 2 LAST PATH I76
J 0
(-3600 7775);
DISPLAY 0.680851 (-3600 7775);
DISPLAY INVISIBLE (-3600 7775);
FORCEADD VCC_CORE..1
(-3300 8275);
FORCEPROP 3 LASTPIN (-3300 8225) SIG_NAME P3V3_AUX\g
J 0
(-3290 8235);
DISPLAY 0.659574 (-3290 8235);
PAINT MONO (-3290 8235);
DISPLAY INVISIBLE (-3290 8235);
FORCEPROP 1 LAST HDL_POWER P3V3_AUX
J 1
(-3300 8325);
DISPLAY 0.489362 (-3300 8325);
PAINT GREEN (-3300 8325);
FORCEPROP 2 LAST CDS_LIB pure_quanta_power
J 0
(-3300 8275);
DISPLAY INVISIBLE (-3300 8275);
FORCEPROP 1 LAST PATH I77
J 0
(-3250 8300);
DISPLAY 0.872340 (-3250 8300);
PAINT AQUA (-3250 8300);
DISPLAY INVISIBLE (-3250 8300);
FORCEADD Q_RES..1
(-2900 8150);
FORCEPROP 1 LAST LOCATION R8167
J 0
(-2950 8200);
DISPLAY 0.489362 (-2950 8200);
PAINT SKYBLUE (-2950 8200);
FORCEPROP 0 LAST $SEC 1
J 0
(-2950 8225);
DISPLAY 0.680851 (-2950 8225);
PAINT MONO (-2950 8225);
DISPLAY INVISIBLE (-2950 8225);
FORCEPROP 0 LAST CDS_SEC 1
J 0
(-2950 8225);
DISPLAY 1.021277 (-2950 8225);
DISPLAY INVISIBLE (-2950 8225);
FORCEPROP 1 LASTPIN (-3000 8150) $PN 1
J 0
(-2988 8162);
DISPLAY 0.489362 (-2988 8162);
PAINT MONO (-2988 8162);
FORCEPROP 1 LASTPIN (-2800 8150) $PN 2
J 0
(-2838 8162);
DISPLAY 0.489362 (-2838 8162);
PAINT MONO (-2838 8162);
FORCEPROP 1 LAST MATERIAL CHIP
J 0
(-3225 8050);
DISPLAY 0.489362 (-3225 8050);
PAINT SKYBLUE (-3225 8050);
FORCEPROP 1 LAST TOLERANCE 1%
J 0
(-2775 8175);
DISPLAY 0.489362 (-2775 8175);
PAINT SKYBLUE (-2775 8175);
FORCEPROP 1 LAST WATTAGE 1/16W
J 0
(-2800 8100);
DISPLAY 0.489362 (-2800 8100);
PAINT SKYBLUE (-2800 8100);
FORCEPROP 1 LAST PACK_TYPE 0402LF
J 0
(-2800 8050);
DISPLAY 0.489362 (-2800 8050);
PAINT SKYBLUE (-2800 8050);
FORCEPROP 1 LAST VALUE 1K
J 2
(-3050 8175);
DISPLAY 0.489362 (-3050 8175);
PAINT SKYBLUE (-3050 8175);
FORCEPROP 2 LAST CDS_LIB pure_quanta
J 0
(-2900 8150);
DISPLAY INVISIBLE (-2900 8150);
FORCEPROP 1 LAST PATH I78
J 0
(-2950 8300);
DISPLAY 0.978723 (-2950 8300);
PAINT WHITE (-2950 8300);
DISPLAY INVISIBLE (-2950 8300);
FORCEPROP 1 LAST PART_NUMBER CS21002FB06
J 0
(-3225 8100);
DISPLAY 0.489362 (-3225 8100);
PAINT SKYBLUE (-3225 8100);
DISPLAY INVISIBLE (-3225 8100);
FORCEADD Q_RES..1
(-2700 6425);
FORCEPROP 1 LAST LOCATION R8177
J 0
(-2750 6475);
DISPLAY 0.489362 (-2750 6475);
PAINT SKYBLUE (-2750 6475);
FORCEPROP 0 LAST $SEC 1
J 0
(-2750 6500);
DISPLAY 0.680851 (-2750 6500);
PAINT MONO (-2750 6500);
DISPLAY INVISIBLE (-2750 6500);
FORCEPROP 0 LAST CDS_SEC 1
J 0
(-2750 6500);
DISPLAY 1.021277 (-2750 6500);
DISPLAY INVISIBLE (-2750 6500);
FORCEPROP 1 LASTPIN (-2800 6425) $PN 1
J 0
(-2788 6437);
DISPLAY 0.489362 (-2788 6437);
PAINT MONO (-2788 6437);
FORCEPROP 1 LASTPIN (-2600 6425) $PN 2
J 0
(-2638 6437);
DISPLAY 0.489362 (-2638 6437);
PAINT MONO (-2638 6437);
FORCEPROP 1 LAST VALUE 33
J 2
(-2825 6450);
DISPLAY 0.489362 (-2825 6450);
PAINT SKYBLUE (-2825 6450);
FORCEPROP 1 LAST PACK_TYPE 0402LF
J 0
(-2600 6350);
DISPLAY 0.489362 (-2600 6350);
PAINT SKYBLUE (-2600 6350);
FORCEPROP 1 LAST TOLERANCE 5%
J 0
(-2575 6450);
DISPLAY 0.489362 (-2575 6450);
PAINT SKYBLUE (-2575 6450);
FORCEPROP 1 LAST WATTAGE 1/16W
J 0
(-2600 6375);
DISPLAY 0.489362 (-2600 6375);
PAINT SKYBLUE (-2600 6375);
FORCEPROP 1 LAST MATERIAL CHIP
J 0
(-2950 6350);
DISPLAY 0.489362 (-2950 6350);
PAINT SKYBLUE (-2950 6350);
FORCEPROP 2 LAST CDS_LIB pure_quanta
J 0
(-2700 6425);
DISPLAY INVISIBLE (-2700 6425);
FORCEPROP 1 LAST PATH I79
J 0
(-2750 6575);
DISPLAY 0.978723 (-2750 6575);
PAINT WHITE (-2750 6575);
DISPLAY INVISIBLE (-2750 6575);
FORCEPROP 1 LAST PART_NUMBER CS03302JB10
J 0
(-2950 6375);
DISPLAY 0.489362 (-2950 6375);
PAINT SKYBLUE (-2950 6375);
DISPLAY INVISIBLE (-2950 6375);
FORCEADD OFFPAGE..4
R 2
(-5675 7275);
FORCEPROP 2 LAST $XR0 54 
J 0
(-5926 7275);
DISPLAY 0.638298 (-5926 7275);
PAINT MONO (-5926 7275);
FORCEPROP 2 LAST CDS_LIB standard
J 0
(-5675 7275);
DISPLAY INVISIBLE (-5675 7275);
FORCEPROP 1 LAST OFFPAGE TRUE
J 2
(-6000 7150);
DISPLAY 0.872340 (-6000 7150);
PAINT GREEN (-6000 7150);
DISPLAY INVISIBLE (-6000 7150);
FORCEPROP 1 LAST COMMENT_BODY TRUE
J 2
(-5650 7175);
DISPLAY 0.872340 (-5650 7175);
PAINT GREEN (-5650 7175);
DISPLAY INVISIBLE (-5650 7175);
FORCEPROP 2 LAST PATH I8
J 0
(-5875 7325);
DISPLAY 0.680851 (-5875 7325);
DISPLAY INVISIBLE (-5875 7325);
FORCEADD Q_RES..1
(-2700 6575);
FORCEPROP 1 LAST LOCATION R8176
J 0
(-2750 6625);
DISPLAY 0.489362 (-2750 6625);
PAINT SKYBLUE (-2750 6625);
FORCEPROP 0 LAST $SEC 1
J 0
(-2750 6650);
DISPLAY 0.680851 (-2750 6650);
PAINT MONO (-2750 6650);
DISPLAY INVISIBLE (-2750 6650);
FORCEPROP 0 LAST CDS_SEC 1
J 0
(-2750 6650);
DISPLAY 1.021277 (-2750 6650);
DISPLAY INVISIBLE (-2750 6650);
FORCEPROP 1 LASTPIN (-2800 6575) $PN 1
J 0
(-2788 6587);
DISPLAY 0.489362 (-2788 6587);
PAINT MONO (-2788 6587);
FORCEPROP 1 LASTPIN (-2600 6575) $PN 2
J 0
(-2638 6587);
DISPLAY 0.489362 (-2638 6587);
PAINT MONO (-2638 6587);
FORCEPROP 1 LAST PACK_TYPE 0402LF
J 0
(-2600 6500);
DISPLAY 0.489362 (-2600 6500);
PAINT SKYBLUE (-2600 6500);
FORCEPROP 1 LAST WATTAGE 1/16W
J 0
(-2600 6525);
DISPLAY 0.489362 (-2600 6525);
PAINT SKYBLUE (-2600 6525);
FORCEPROP 1 LAST TOLERANCE 5%
J 0
(-2575 6600);
DISPLAY 0.489362 (-2575 6600);
PAINT SKYBLUE (-2575 6600);
FORCEPROP 1 LAST VALUE 0
J 2
(-2825 6600);
DISPLAY 0.489362 (-2825 6600);
PAINT SKYBLUE (-2825 6600);
FORCEPROP 1 LAST MATERIAL CHIP
J 0
(-2950 6500);
DISPLAY 0.489362 (-2950 6500);
PAINT SKYBLUE (-2950 6500);
FORCEPROP 2 LAST CDS_LIB pure_quanta
J 0
(-2700 6575);
DISPLAY INVISIBLE (-2700 6575);
FORCEPROP 1 LAST PATH I80
J 0
(-2750 6725);
DISPLAY 0.978723 (-2750 6725);
PAINT WHITE (-2750 6725);
DISPLAY INVISIBLE (-2750 6725);
FORCEPROP 1 LAST PART_NUMBER CS00002JB13
J 0
(-2950 6525);
DISPLAY 0.489362 (-2950 6525);
PAINT SKYBLUE (-2950 6525);
DISPLAY INVISIBLE (-2950 6525);
FORCEADD Q_RES..1
(-2700 6725);
FORCEPROP 1 LAST LOCATION R175
J 0
(-2750 6775);
DISPLAY 0.489362 (-2750 6775);
PAINT SKYBLUE (-2750 6775);
FORCEPROP 0 LAST $SEC 1
J 0
(-2750 6800);
DISPLAY 0.680851 (-2750 6800);
PAINT MONO (-2750 6800);
DISPLAY INVISIBLE (-2750 6800);
FORCEPROP 0 LAST CDS_SEC 1
J 0
(-2750 6800);
DISPLAY 1.021277 (-2750 6800);
DISPLAY INVISIBLE (-2750 6800);
FORCEPROP 1 LASTPIN (-2800 6725) $PN 1
J 0
(-2788 6737);
DISPLAY 0.489362 (-2788 6737);
PAINT MONO (-2788 6737);
FORCEPROP 1 LASTPIN (-2600 6725) $PN 2
J 0
(-2638 6737);
DISPLAY 0.489362 (-2638 6737);
PAINT MONO (-2638 6737);
FORCEPROP 1 LAST PACK_TYPE 0402LF
J 0
(-2600 6650);
DISPLAY 0.489362 (-2600 6650);
PAINT SKYBLUE (-2600 6650);
FORCEPROP 1 LAST WATTAGE 1/16W
J 0
(-2600 6675);
DISPLAY 0.489362 (-2600 6675);
PAINT SKYBLUE (-2600 6675);
FORCEPROP 1 LAST TOLERANCE 5%
J 0
(-2575 6750);
DISPLAY 0.489362 (-2575 6750);
PAINT SKYBLUE (-2575 6750);
FORCEPROP 1 LAST VALUE 0
J 2
(-2825 6750);
DISPLAY 0.489362 (-2825 6750);
PAINT SKYBLUE (-2825 6750);
FORCEPROP 1 LAST MATERIAL CHIP
J 0
(-2950 6650);
DISPLAY 0.489362 (-2950 6650);
PAINT SKYBLUE (-2950 6650);
FORCEPROP 2 LAST CDS_LIB pure_quanta
J 0
(-2700 6725);
DISPLAY INVISIBLE (-2700 6725);
FORCEPROP 1 LAST PATH I81
J 0
(-2750 6875);
DISPLAY 0.978723 (-2750 6875);
PAINT WHITE (-2750 6875);
DISPLAY INVISIBLE (-2750 6875);
FORCEPROP 1 LAST PART_NUMBER CS00002JB13
J 0
(-2950 6675);
DISPLAY 0.489362 (-2950 6675);
PAINT SKYBLUE (-2950 6675);
DISPLAY INVISIBLE (-2950 6675);
FORCEADD Q_RES..1
(-2800 6975);
FORCEPROP 1 LAST LOCATION PR172
J 0
(-2850 7025);
DISPLAY 0.489362 (-2850 7025);
PAINT SKYBLUE (-2850 7025);
FORCEPROP 0 LAST $SEC 1
J 0
(-2850 7050);
DISPLAY 0.680851 (-2850 7050);
PAINT MONO (-2850 7050);
DISPLAY INVISIBLE (-2850 7050);
FORCEPROP 0 LAST CDS_SEC 1
J 0
(-2850 7050);
DISPLAY 1.021277 (-2850 7050);
DISPLAY INVISIBLE (-2850 7050);
FORCEPROP 1 LASTPIN (-2900 6975) $PN 1
J 0
(-2888 6987);
DISPLAY 0.489362 (-2888 6987);
PAINT MONO (-2888 6987);
FORCEPROP 1 LASTPIN (-2700 6975) $PN 2
J 0
(-2738 6987);
DISPLAY 0.489362 (-2738 6987);
PAINT MONO (-2738 6987);
FORCEPROP 1 LAST TOLERANCE 5%
J 0
(-2675 7000);
DISPLAY 0.489362 (-2675 7000);
PAINT SKYBLUE (-2675 7000);
FORCEPROP 1 LAST VALUE 0
J 2
(-2925 7000);
DISPLAY 0.489362 (-2925 7000);
PAINT SKYBLUE (-2925 7000);
FORCEPROP 1 LAST PACK_TYPE 0402LF
J 0
(-2700 6900);
DISPLAY 0.489362 (-2700 6900);
PAINT SKYBLUE (-2700 6900);
FORCEPROP 1 LAST WATTAGE 1/16W
J 0
(-2700 6925);
DISPLAY 0.489362 (-2700 6925);
PAINT SKYBLUE (-2700 6925);
FORCEPROP 1 LAST MATERIAL CHIP
J 0
(-3050 6900);
DISPLAY 0.489362 (-3050 6900);
PAINT SKYBLUE (-3050 6900);
FORCEPROP 2 LAST CDS_LIB pure_quanta
J 0
(-2800 6975);
DISPLAY INVISIBLE (-2800 6975);
FORCEPROP 1 LAST PATH I82
J 0
(-2850 7125);
DISPLAY 0.978723 (-2850 7125);
PAINT WHITE (-2850 7125);
DISPLAY INVISIBLE (-2850 7125);
FORCEPROP 1 LAST PART_NUMBER CS00002JB13
J 0
(-3050 6925);
DISPLAY 0.489362 (-3050 6925);
PAINT SKYBLUE (-3050 6925);
DISPLAY INVISIBLE (-3050 6925);
FORCEADD Q_RES..1
(-2800 7125);
FORCEPROP 1 LAST LOCATION R8171
J 0
(-2850 7175);
DISPLAY 0.489362 (-2850 7175);
PAINT SKYBLUE (-2850 7175);
FORCEPROP 0 LAST $SEC 1
J 0
(-2850 7200);
DISPLAY 0.680851 (-2850 7200);
PAINT MONO (-2850 7200);
DISPLAY INVISIBLE (-2850 7200);
FORCEPROP 0 LAST CDS_SEC 1
J 0
(-2850 7200);
DISPLAY 1.021277 (-2850 7200);
DISPLAY INVISIBLE (-2850 7200);
FORCEPROP 1 LASTPIN (-2900 7125) $PN 1
J 0
(-2888 7137);
DISPLAY 0.489362 (-2888 7137);
PAINT MONO (-2888 7137);
FORCEPROP 1 LASTPIN (-2700 7125) $PN 2
J 0
(-2738 7137);
DISPLAY 0.489362 (-2738 7137);
PAINT MONO (-2738 7137);
FORCEPROP 1 LAST TOLERANCE 1%
J 0
(-2675 7150);
DISPLAY 0.489362 (-2675 7150);
PAINT SKYBLUE (-2675 7150);
FORCEPROP 1 LAST VALUE 49.9
J 2
(-2925 7150);
DISPLAY 0.489362 (-2925 7150);
PAINT SKYBLUE (-2925 7150);
FORCEPROP 1 LAST MATERIAL CHIP
J 0
(-3050 7050);
DISPLAY 0.489362 (-3050 7050);
PAINT SKYBLUE (-3050 7050);
FORCEPROP 1 LAST WATTAGE 1/16W
J 0
(-2700 7075);
DISPLAY 0.489362 (-2700 7075);
PAINT SKYBLUE (-2700 7075);
FORCEPROP 1 LAST PACK_TYPE 0402LF
J 0
(-2700 7050);
DISPLAY 0.489362 (-2700 7050);
PAINT SKYBLUE (-2700 7050);
FORCEPROP 2 LAST CDS_LIB pure_quanta
J 0
(-2800 7125);
DISPLAY INVISIBLE (-2800 7125);
FORCEPROP 1 LAST PATH I83
J 0
(-2850 7275);
DISPLAY 0.978723 (-2850 7275);
PAINT WHITE (-2850 7275);
DISPLAY INVISIBLE (-2850 7275);
FORCEPROP 1 LAST PART_NUMBER CS04992FB07
J 0
(-3050 7075);
DISPLAY 0.489362 (-3050 7075);
PAINT SKYBLUE (-3050 7075);
DISPLAY INVISIBLE (-3050 7075);
FORCEADD Q_RES..1
(-2675 7725);
FORCEPROP 1 LAST LOCATION R8179
J 0
(-2725 7750);
DISPLAY 0.489362 (-2725 7750);
PAINT SKYBLUE (-2725 7750);
FORCEPROP 0 LAST $SEC 1
J 0
(-2550 7775);
DISPLAY 0.680851 (-2550 7775);
PAINT MONO (-2550 7775);
DISPLAY INVISIBLE (-2550 7775);
FORCEPROP 0 LAST CDS_SEC 1
J 0
(-2550 7775);
DISPLAY 1.021277 (-2550 7775);
DISPLAY INVISIBLE (-2550 7775);
FORCEPROP 1 LASTPIN (-2775 7725) $PN 1
J 0
(-2763 7737);
DISPLAY 0.489362 (-2763 7737);
PAINT MONO (-2763 7737);
FORCEPROP 1 LASTPIN (-2575 7725) $PN 2
J 0
(-2613 7737);
DISPLAY 0.489362 (-2613 7737);
PAINT MONO (-2613 7737);
FORCEPROP 1 LAST MATERIAL CHIP
J 0
(-2925 7650);
DISPLAY 0.489362 (-2925 7650);
PAINT SKYBLUE (-2925 7650);
FORCEPROP 1 LAST PACK_TYPE 0402LF
J 0
(-2575 7650);
DISPLAY 0.489362 (-2575 7650);
PAINT SKYBLUE (-2575 7650);
FORCEPROP 1 LAST VALUE 0
J 2
(-2800 7750);
DISPLAY 0.489362 (-2800 7750);
PAINT SKYBLUE (-2800 7750);
FORCEPROP 1 LAST WATTAGE 1/16W
J 0
(-2575 7675);
DISPLAY 0.489362 (-2575 7675);
PAINT SKYBLUE (-2575 7675);
FORCEPROP 1 LAST TOLERANCE 5%
J 0
(-2550 7750);
DISPLAY 0.489362 (-2550 7750);
PAINT SKYBLUE (-2550 7750);
FORCEPROP 2 LAST CDS_LIB pure_quanta
J 0
(-2675 7725);
DISPLAY INVISIBLE (-2675 7725);
FORCEPROP 1 LAST PATH I84
J 0
(-2725 7875);
DISPLAY 0.978723 (-2725 7875);
PAINT WHITE (-2725 7875);
DISPLAY INVISIBLE (-2725 7875);
FORCEPROP 1 LAST PART_NUMBER CS00002JB13
J 0
(-2925 7675);
DISPLAY 0.489362 (-2925 7675);
PAINT SKYBLUE (-2925 7675);
DISPLAY INVISIBLE (-2925 7675);
FORCEADD Q_RES..1
(-2675 7875);
FORCEPROP 1 LAST LOCATION R8178
J 0
(-2725 7925);
DISPLAY 0.489362 (-2725 7925);
PAINT SKYBLUE (-2725 7925);
FORCEPROP 0 LAST $SEC 1
J 0
(-2550 7925);
DISPLAY 0.680851 (-2550 7925);
PAINT MONO (-2550 7925);
DISPLAY INVISIBLE (-2550 7925);
FORCEPROP 0 LAST CDS_SEC 1
J 0
(-2550 7925);
DISPLAY 1.021277 (-2550 7925);
DISPLAY INVISIBLE (-2550 7925);
FORCEPROP 1 LASTPIN (-2775 7875) $PN 1
J 0
(-2763 7887);
DISPLAY 0.489362 (-2763 7887);
PAINT MONO (-2763 7887);
FORCEPROP 1 LASTPIN (-2575 7875) $PN 2
J 0
(-2613 7887);
DISPLAY 0.489362 (-2613 7887);
PAINT MONO (-2613 7887);
FORCEPROP 1 LAST PACK_TYPE 0402LF
J 0
(-2575 7800);
DISPLAY 0.489362 (-2575 7800);
PAINT SKYBLUE (-2575 7800);
FORCEPROP 1 LAST WATTAGE 1/16W
J 0
(-2575 7825);
DISPLAY 0.489362 (-2575 7825);
PAINT SKYBLUE (-2575 7825);
FORCEPROP 1 LAST MATERIAL CHIP
J 0
(-2925 7800);
DISPLAY 0.489362 (-2925 7800);
PAINT SKYBLUE (-2925 7800);
FORCEPROP 1 LAST VALUE 33
J 2
(-2800 7900);
DISPLAY 0.489362 (-2800 7900);
PAINT SKYBLUE (-2800 7900);
FORCEPROP 1 LAST TOLERANCE 5%
J 0
(-2550 7900);
DISPLAY 0.489362 (-2550 7900);
PAINT SKYBLUE (-2550 7900);
FORCEPROP 2 LAST CDS_LIB pure_quanta
J 0
(-2675 7875);
DISPLAY INVISIBLE (-2675 7875);
FORCEPROP 1 LAST PATH I85
J 0
(-2725 8025);
DISPLAY 0.978723 (-2725 8025);
PAINT WHITE (-2725 8025);
DISPLAY INVISIBLE (-2725 8025);
FORCEPROP 1 LAST PART_NUMBER CS03302JB10
J 0
(-2925 7825);
DISPLAY 0.489362 (-2925 7825);
PAINT SKYBLUE (-2925 7825);
DISPLAY INVISIBLE (-2925 7825);
FORCEADD Q_CAP..2
(-2000 7600);
FORCEPROP 1 LAST LOCATION C249
J 1
(-2000 7650);
DISPLAY 0.489362 (-2000 7650);
PAINT SKYBLUE (-2000 7650);
FORCEPROP 0 LAST $SEC 1
J 0
(-2000 7700);
DISPLAY 0.680851 (-2000 7700);
PAINT MONO (-2000 7700);
DISPLAY INVISIBLE (-2000 7700);
FORCEPROP 0 LAST CDS_SEC 1
J 0
(-2000 7700);
DISPLAY 1.021277 (-2000 7700);
DISPLAY INVISIBLE (-2000 7700);
FORCEPROP 1 LASTPIN (-2100 7600) $PN 1
J 0
(-2110 7615);
DISPLAY 0.489362 (-2110 7615);
PAINT MONO (-2110 7615);
FORCEPROP 1 LASTPIN (-1900 7600) $PN 2
J 0
(-1915 7615);
DISPLAY 0.489362 (-1915 7615);
PAINT MONO (-1915 7615);
FORCEPROP 1 LAST MATERIAL X7R
J 0
(-2425 7550);
DISPLAY 0.489362 (-2425 7550);
PAINT SKYBLUE (-2425 7550);
FORCEPROP 1 LAST TOLERANCE 5%
J 0
(-1900 7550);
DISPLAY 0.489362 (-1900 7550);
PAINT SKYBLUE (-1900 7550);
FORCEPROP 1 LAST PACK_TYPE 0402
J 0
(-1900 7575);
DISPLAY 0.489362 (-1900 7575);
PAINT SKYBLUE (-1900 7575);
FORCEPROP 1 LAST VALUE 1000PF
J 2
(-2175 7625);
DISPLAY 0.489362 (-2175 7625);
PAINT SKYBLUE (-2175 7625);
FORCEPROP 1 LAST VOLTAGE 50V
J 0
(-1850 7625);
DISPLAY 0.489362 (-1850 7625);
PAINT SKYBLUE (-1850 7625);
FORCEPROP 2 LAST CDS_LIB pure_quanta
J 0
(-2000 7600);
DISPLAY INVISIBLE (-2000 7600);
FORCEPROP 1 LAST PATH I86
J 0
(-2000 7800);
DISPLAY 0.978723 (-2000 7800);
PAINT WHITE (-2000 7800);
DISPLAY INVISIBLE (-2000 7800);
FORCEPROP 1 LAST PART_NUMBER TMP_QCH21006JB10
J 0
(-2425 7575);
DISPLAY 0.489362 (-2425 7575);
PAINT SKYBLUE (-2425 7575);
DISPLAY INVISIBLE (-2425 7575);
FORCEADD UNIVERSAL_GND..1
(-1775 7525);
FORCEPROP 3 LASTPIN (-1775 7575) SIG_NAME GND\g
J 0
(-1765 7585);
DISPLAY 0.659574 (-1765 7585);
PAINT MONO (-1765 7585);
DISPLAY INVISIBLE (-1765 7585);
FORCEPROP 2 LAST CDS_LIB pure_quanta_power
J 0
(-1775 7525);
DISPLAY INVISIBLE (-1775 7525);
FORCEPROP 1 LAST HDL_POWER GND
J 1
(-1750 7450);
DISPLAY 0.872340 (-1750 7450);
PAINT GREEN (-1750 7450);
DISPLAY INVISIBLE (-1750 7450);
FORCEPROP 1 LAST PATH I87
J 0
(-1700 7525);
DISPLAY 0.872340 (-1700 7525);
PAINT AQUA (-1700 7525);
DISPLAY INVISIBLE (-1700 7525);
FORCEADD Q_CAP..2
(-2025 8150);
FORCEPROP 1 LAST LOCATION C248
J 1
(-2025 8225);
DISPLAY 0.489362 (-2025 8225);
PAINT SKYBLUE (-2025 8225);
FORCEPROP 0 LAST $SEC 1
J 0
(-2025 8250);
DISPLAY 0.680851 (-2025 8250);
PAINT MONO (-2025 8250);
DISPLAY INVISIBLE (-2025 8250);
FORCEPROP 0 LAST CDS_SEC 1
J 0
(-2025 8250);
DISPLAY 1.021277 (-2025 8250);
DISPLAY INVISIBLE (-2025 8250);
FORCEPROP 1 LASTPIN (-2125 8150) $PN 1
J 0
(-2135 8165);
DISPLAY 0.489362 (-2135 8165);
PAINT MONO (-2135 8165);
FORCEPROP 1 LASTPIN (-1925 8150) $PN 2
J 0
(-1940 8165);
DISPLAY 0.489362 (-1940 8165);
PAINT MONO (-1940 8165);
FORCEPROP 1 LAST MATERIAL EMPTY
J 0
(-2300 8025);
DISPLAY 0.489362 (-2300 8025);
PAINT RED (-2300 8025);
FORCEPROP 1 LAST PACK_TYPE 0402
J 0
(-1900 8075);
DISPLAY 0.489362 (-1900 8075);
PAINT SKYBLUE (-1900 8075);
FORCEPROP 1 LAST VOLTAGE 50V
J 0
(-1925 8200);
DISPLAY 0.489362 (-1925 8200);
PAINT SKYBLUE (-1925 8200);
FORCEPROP 1 LAST VALUE 1000PF
J 2
(-2150 8200);
DISPLAY 0.489362 (-2150 8200);
PAINT SKYBLUE (-2150 8200);
FORCEPROP 1 LAST TOLERANCE 5%
J 0
(-1900 8025);
DISPLAY 0.489362 (-1900 8025);
PAINT SKYBLUE (-1900 8025);
FORCEPROP 2 LAST CDS_LIB pure_quanta
J 0
(-2025 8150);
DISPLAY INVISIBLE (-2025 8150);
FORCEPROP 1 LAST PATH I88
J 0
(-2025 8350);
DISPLAY 0.978723 (-2025 8350);
PAINT WHITE (-2025 8350);
DISPLAY INVISIBLE (-2025 8350);
FORCEPROP 1 LAST PART_NUMBER TMP_QCH21006JB10
J 1
(-2175 8075);
DISPLAY 0.489362 (-2175 8075);
PAINT SKYBLUE (-2175 8075);
DISPLAY INVISIBLE (-2175 8075);
FORCEADD UNIVERSAL_GND..1
(-1775 8075);
FORCEPROP 3 LASTPIN (-1775 8125) SIG_NAME GND\g
J 0
(-1765 8135);
DISPLAY 0.659574 (-1765 8135);
PAINT MONO (-1765 8135);
DISPLAY INVISIBLE (-1765 8135);
FORCEPROP 2 LAST CDS_LIB pure_quanta_power
J 0
(-1775 8075);
DISPLAY INVISIBLE (-1775 8075);
FORCEPROP 1 LAST HDL_POWER GND
J 1
(-1750 8000);
DISPLAY 0.872340 (-1750 8000);
PAINT GREEN (-1750 8000);
DISPLAY INVISIBLE (-1750 8000);
FORCEPROP 1 LAST PATH I89
J 0
(-1700 8075);
DISPLAY 0.872340 (-1700 8075);
PAINT AQUA (-1700 8075);
DISPLAY INVISIBLE (-1700 8075);
FORCEADD OFFPAGE..4
R 2
(-5675 7425);
FORCEPROP 2 LAST $XR0 54 
J 0
(-5926 7425);
DISPLAY 0.638298 (-5926 7425);
PAINT MONO (-5926 7425);
FORCEPROP 2 LAST CDS_LIB standard
J 0
(-5675 7425);
DISPLAY INVISIBLE (-5675 7425);
FORCEPROP 1 LAST OFFPAGE TRUE
J 2
(-6000 7300);
DISPLAY 0.872340 (-6000 7300);
PAINT GREEN (-6000 7300);
DISPLAY INVISIBLE (-6000 7300);
FORCEPROP 1 LAST COMMENT_BODY TRUE
J 2
(-5650 7325);
DISPLAY 0.872340 (-5650 7325);
PAINT GREEN (-5650 7325);
DISPLAY INVISIBLE (-5650 7325);
FORCEPROP 2 LAST PATH I9
J 0
(-5875 7475);
DISPLAY 0.680851 (-5875 7475);
DISPLAY INVISIBLE (-5875 7475);
FORCEADD UNIVERSAL_GND..1
(-150 2200);
FORCEPROP 3 LASTPIN (-150 2250) SIG_NAME GND\g
J 0
(-140 2260);
DISPLAY 0.659574 (-140 2260);
PAINT MONO (-140 2260);
DISPLAY INVISIBLE (-140 2260);
FORCEPROP 2 LAST CDS_LIB pure_quanta_power
J 0
(-150 2200);
DISPLAY INVISIBLE (-150 2200);
FORCEPROP 1 LAST HDL_POWER GND
J 1
(-125 2125);
DISPLAY 0.872340 (-125 2125);
PAINT GREEN (-125 2125);
DISPLAY INVISIBLE (-125 2125);
FORCEPROP 1 LAST PATH I90
J 0
(-75 2200);
DISPLAY 0.872340 (-75 2200);
PAINT AQUA (-75 2200);
DISPLAY INVISIBLE (-75 2200);
FORCEADD Q_CAP..1
(-150 2475);
FORCEPROP 1 LAST LOCATION PC250
J 0
(-100 2575);
DISPLAY 0.489362 (-100 2575);
PAINT SKYBLUE (-100 2575);
FORCEPROP 0 LAST $SEC 1
J 0
(-100 2600);
DISPLAY 0.680851 (-100 2600);
PAINT MONO (-100 2600);
DISPLAY INVISIBLE (-100 2600);
FORCEPROP 0 LAST CDS_SEC 1
J 0
(-100 2600);
DISPLAY 1.021277 (-100 2600);
DISPLAY INVISIBLE (-100 2600);
FORCEPROP 1 LASTPIN (-150 2575) $PN 1
J 0
(-140 2555);
DISPLAY 0.489362 (-140 2555);
PAINT MONO (-140 2555);
FORCEPROP 1 LASTPIN (-150 2375) $PN 2
J 0
(-140 2355);
DISPLAY 0.489362 (-140 2355);
PAINT MONO (-140 2355);
FORCEPROP 1 LAST MATERIAL X7R
J 0
(-100 2375);
DISPLAY 0.489362 (-100 2375);
PAINT SKYBLUE (-100 2375);
FORCEPROP 1 LAST VALUE 470PF
J 0
(-100 2525);
DISPLAY 0.489362 (-100 2525);
PAINT SKYBLUE (-100 2525);
FORCEPROP 1 LAST PACK_TYPE 0402
J 0
(-100 2275);
DISPLAY 0.489362 (-100 2275);
PAINT SKYBLUE (-100 2275);
FORCEPROP 1 LAST TOLERANCE 10%
J 0
(-100 2425);
DISPLAY 0.489362 (-100 2425);
PAINT SKYBLUE (-100 2425);
FORCEPROP 1 LAST VOLTAGE 50V
J 0
(-100 2475);
DISPLAY 0.489362 (-100 2475);
PAINT SKYBLUE (-100 2475);
FORCEPROP 2 LAST CDS_LIB pure_quanta
J 0
(-150 2475);
DISPLAY INVISIBLE (-150 2475);
FORCEPROP 1 LAST PATH I91
J 0
(-100 2625);
DISPLAY 0.978723 (-100 2625);
PAINT WHITE (-100 2625);
DISPLAY INVISIBLE (-100 2625);
FORCEPROP 1 LAST PART_NUMBER TMP_QCH14706KB18
J 0
(-100 2325);
DISPLAY 0.489362 (-100 2325);
PAINT SKYBLUE (-100 2325);
DISPLAY INVISIBLE (-100 2325);
FORCEADD OFFPAGE..4
(175 2675);
FORCEPROP 2 LAST $XR0 211 
J 0
(361 2675);
DISPLAY 0.638298 (361 2675);
PAINT MONO (361 2675);
FORCEPROP 2 LAST $XR1 212 
J 0
(361 2639);
DISPLAY 0.638298 (361 2639);
PAINT MONO (361 2639);
FORCEPROP 2 LAST $XR2 213 
J 0
(361 2711);
DISPLAY 0.638298 (361 2711);
PAINT MONO (361 2711);
FORCEPROP 2 LAST CDS_LIB standard
J 0
(175 2675);
DISPLAY INVISIBLE (175 2675);
FORCEPROP 1 LAST OFFPAGE TRUE
J 0
(500 2550);
DISPLAY 0.872340 (500 2550);
PAINT GREEN (500 2550);
DISPLAY INVISIBLE (500 2550);
FORCEPROP 1 LAST COMMENT_BODY TRUE
J 0
(150 2575);
DISPLAY 0.872340 (150 2575);
PAINT GREEN (150 2575);
DISPLAY INVISIBLE (150 2575);
FORCEPROP 2 LAST PATH I92
J 0
(375 2750);
DISPLAY 0.680851 (375 2750);
DISPLAY INVISIBLE (375 2750);
FORCEADD UNIVERSAL_GND..1
(475 2550);
FORCEPROP 3 LASTPIN (475 2600) SIG_NAME GND\g
J 0
(485 2610);
DISPLAY 0.659574 (485 2610);
PAINT MONO (485 2610);
DISPLAY INVISIBLE (485 2610);
FORCEPROP 2 LAST CDS_LIB pure_quanta_power
J 0
(475 2550);
DISPLAY INVISIBLE (475 2550);
FORCEPROP 1 LAST HDL_POWER GND
J 1
(500 2475);
DISPLAY 0.872340 (500 2475);
PAINT GREEN (500 2475);
DISPLAY INVISIBLE (500 2475);
FORCEPROP 1 LAST PATH I93
J 0
(550 2550);
DISPLAY 0.872340 (550 2550);
PAINT AQUA (550 2550);
DISPLAY INVISIBLE (550 2550);
FORCEADD Q_CAP..1
(475 2800);
FORCEPROP 1 LAST LOCATION PC253
J 0
(525 2900);
DISPLAY 0.489362 (525 2900);
PAINT SKYBLUE (525 2900);
FORCEPROP 0 LAST $SEC 1
J 0
(525 2925);
DISPLAY 0.680851 (525 2925);
PAINT MONO (525 2925);
DISPLAY INVISIBLE (525 2925);
FORCEPROP 0 LAST CDS_SEC 1
J 0
(525 2925);
DISPLAY 1.021277 (525 2925);
DISPLAY INVISIBLE (525 2925);
FORCEPROP 1 LASTPIN (475 2900) $PN 1
J 0
(485 2880);
DISPLAY 0.489362 (485 2880);
PAINT MONO (485 2880);
FORCEPROP 1 LASTPIN (475 2700) $PN 2
J 0
(485 2680);
DISPLAY 0.489362 (485 2680);
PAINT MONO (485 2680);
FORCEPROP 1 LAST MATERIAL X7R
J 0
(525 2700);
DISPLAY 0.489362 (525 2700);
PAINT SKYBLUE (525 2700);
FORCEPROP 1 LAST TOLERANCE 10%
J 0
(525 2750);
DISPLAY 0.489362 (525 2750);
PAINT SKYBLUE (525 2750);
FORCEPROP 1 LAST VALUE 470PF
J 0
(525 2850);
DISPLAY 0.489362 (525 2850);
PAINT SKYBLUE (525 2850);
FORCEPROP 1 LAST VOLTAGE 50V
J 0
(525 2800);
DISPLAY 0.489362 (525 2800);
PAINT SKYBLUE (525 2800);
FORCEPROP 1 LAST PACK_TYPE 0402
J 0
(525 2600);
DISPLAY 0.489362 (525 2600);
PAINT SKYBLUE (525 2600);
FORCEPROP 2 LAST CDS_LIB pure_quanta
J 0
(475 2800);
DISPLAY INVISIBLE (475 2800);
FORCEPROP 1 LAST PATH I94
J 0
(525 2950);
DISPLAY 0.978723 (525 2950);
PAINT WHITE (525 2950);
DISPLAY INVISIBLE (525 2950);
FORCEPROP 1 LAST PART_NUMBER TMP_QCH14706KB18
J 0
(525 2650);
DISPLAY 0.489362 (525 2650);
PAINT SKYBLUE (525 2650);
DISPLAY INVISIBLE (525 2650);
FORCEADD OFFPAGE..4
(425 3475);
FORCEPROP 2 LAST $XR0 215 
J 0
(611 3475);
DISPLAY 0.638298 (611 3475);
PAINT MONO (611 3475);
FORCEPROP 2 LAST CDS_LIB standard
J 0
(425 3475);
DISPLAY INVISIBLE (425 3475);
FORCEPROP 1 LAST OFFPAGE TRUE
J 0
(750 3350);
DISPLAY 0.872340 (750 3350);
PAINT GREEN (750 3350);
DISPLAY INVISIBLE (750 3350);
FORCEPROP 1 LAST COMMENT_BODY TRUE
J 0
(400 3375);
DISPLAY 0.872340 (400 3375);
PAINT GREEN (400 3375);
DISPLAY INVISIBLE (400 3375);
FORCEPROP 2 LAST PATH I95
J 0
(625 3525);
DISPLAY 0.680851 (625 3525);
DISPLAY INVISIBLE (625 3525);
FORCEADD OFFPAGE..2
(425 3575);
FORCEPROP 2 LAST $XR0 215 
J 0
(614 3575);
DISPLAY 0.638298 (614 3575);
PAINT MONO (614 3575);
FORCEPROP 2 LAST CDS_LIB standard
J 0
(425 3575);
DISPLAY INVISIBLE (425 3575);
FORCEPROP 1 LAST OFFPAGE TRUE
J 0
(750 3450);
DISPLAY 0.872340 (750 3450);
PAINT GREEN (750 3450);
DISPLAY INVISIBLE (750 3450);
FORCEPROP 1 LAST COMMENT_BODY TRUE
J 0
(380 3480);
DISPLAY 0.872340 (380 3480);
PAINT GREEN (380 3480);
DISPLAY INVISIBLE (380 3480);
FORCEPROP 2 LAST PATH I96
J 0
(625 3625);
DISPLAY 0.680851 (625 3625);
DISPLAY INVISIBLE (625 3625);
FORCEADD OFFPAGE..4
(450 3775);
FORCEPROP 2 LAST $XR0 215 
J 0
(636 3775);
DISPLAY 0.638298 (636 3775);
PAINT MONO (636 3775);
FORCEPROP 2 LAST CDS_LIB standard
J 0
(450 3775);
DISPLAY INVISIBLE (450 3775);
FORCEPROP 1 LAST OFFPAGE TRUE
J 0
(775 3650);
DISPLAY 0.872340 (775 3650);
PAINT GREEN (775 3650);
DISPLAY INVISIBLE (775 3650);
FORCEPROP 1 LAST COMMENT_BODY TRUE
J 0
(425 3675);
DISPLAY 0.872340 (425 3675);
PAINT GREEN (425 3675);
DISPLAY INVISIBLE (425 3675);
FORCEPROP 2 LAST PATH I97
J 0
(650 3825);
DISPLAY 0.680851 (650 3825);
DISPLAY INVISIBLE (650 3825);
FORCEADD OFFPAGE..4
(750 2975);
FORCEPROP 2 LAST $XR0 215 
J 0
(936 2975);
DISPLAY 0.638298 (936 2975);
PAINT MONO (936 2975);
FORCEPROP 2 LAST $XR1 216 
J 0
(1056 2975);
DISPLAY 0.638298 (1056 2975);
PAINT MONO (1056 2975);
FORCEPROP 2 LAST CDS_LIB standard
J 0
(750 2975);
DISPLAY INVISIBLE (750 2975);
FORCEPROP 1 LAST OFFPAGE TRUE
J 0
(1075 2850);
DISPLAY 0.872340 (1075 2850);
PAINT GREEN (1075 2850);
DISPLAY INVISIBLE (1075 2850);
FORCEPROP 1 LAST COMMENT_BODY TRUE
J 0
(725 2875);
DISPLAY 0.872340 (725 2875);
PAINT GREEN (725 2875);
DISPLAY INVISIBLE (725 2875);
FORCEPROP 2 LAST PATH I98
J 0
(1075 3025);
DISPLAY 0.680851 (1075 3025);
DISPLAY INVISIBLE (1075 3025);
FORCEADD OFFPAGE..2
(450 4175);
FORCEPROP 2 LAST $XR0 216 
J 0
(639 4175);
DISPLAY 0.638298 (639 4175);
PAINT MONO (639 4175);
FORCEPROP 2 LAST CDS_LIB standard
J 0
(450 4175);
DISPLAY INVISIBLE (450 4175);
FORCEPROP 1 LAST OFFPAGE TRUE
J 0
(775 4050);
DISPLAY 0.872340 (775 4050);
PAINT GREEN (775 4050);
DISPLAY INVISIBLE (775 4050);
FORCEPROP 1 LAST COMMENT_BODY TRUE
J 0
(405 4080);
DISPLAY 0.872340 (405 4080);
PAINT GREEN (405 4080);
DISPLAY INVISIBLE (405 4080);
FORCEPROP 2 LAST PATH I99
J 0
(650 4225);
DISPLAY 0.680851 (650 4225);
DISPLAY INVISIBLE (650 4225);
FORCEADD DNS..1
(-4825 6775);
PAINT RED (-4825 6775);
FORCEPROP 2 LAST CDS_LIB mstr_misc
J 0
(-4825 6775);
DISPLAY INVISIBLE (-4825 6775);
FORCEPROP 1 LAST COMMENT_BODY TRUE
R 1
J 0
(-4750 6550);
DISPLAY 0.872340 (-4750 6550);
PAINT GREEN (-4750 6550);
DISPLAY INVISIBLE (-4750 6550);
FORCEADD DNS..1
(-2375 2225);
PAINT RED (-2375 2225);
FORCEPROP 2 LAST CDS_LIB mstr_misc
J 0
(-2375 2225);
DISPLAY INVISIBLE (-2375 2225);
FORCEPROP 1 LAST COMMENT_BODY TRUE
R 1
J 0
(-2300 2000);
DISPLAY 0.872340 (-2300 2000);
PAINT GREEN (-2300 2000);
DISPLAY INVISIBLE (-2300 2000);
FORCEADD DNS..1
(-2425 3000);
PAINT RED (-2425 3000);
FORCEPROP 2 LAST CDS_LIB mstr_misc
J 0
(-2425 3000);
DISPLAY INVISIBLE (-2425 3000);
FORCEPROP 1 LAST COMMENT_BODY TRUE
R 1
J 0
(-2350 2775);
DISPLAY 0.872340 (-2350 2775);
PAINT GREEN (-2350 2775);
DISPLAY INVISIBLE (-2350 2775);
FORCEADD DNS..1
(-5125 7725);
PAINT RED (-5125 7725);
FORCEPROP 2 LAST CDS_LIB mstr_misc
J 0
(-5125 7725);
DISPLAY INVISIBLE (-5125 7725);
FORCEPROP 1 LAST COMMENT_BODY TRUE
R 1
J 0
(-5050 7500);
DISPLAY 0.872340 (-5050 7500);
PAINT GREEN (-5050 7500);
DISPLAY INVISIBLE (-5050 7500);
FORCEADD DNS..1
(-5000 6775);
PAINT RED (-5000 6775);
FORCEPROP 2 LAST CDS_LIB mstr_misc
J 0
(-5000 6775);
DISPLAY INVISIBLE (-5000 6775);
FORCEPROP 1 LAST COMMENT_BODY TRUE
R 1
J 0
(-4925 6550);
DISPLAY 0.872340 (-4925 6550);
PAINT GREEN (-4925 6550);
DISPLAY INVISIBLE (-4925 6550);
FORCEADD DNS..1
(-4325 6775);
PAINT RED (-4325 6775);
FORCEPROP 2 LAST CDS_LIB mstr_misc
J 0
(-4325 6775);
DISPLAY INVISIBLE (-4325 6775);
FORCEPROP 1 LAST COMMENT_BODY TRUE
R 1
J 0
(-4250 6550);
DISPLAY 0.872340 (-4250 6550);
PAINT GREEN (-4250 6550);
DISPLAY INVISIBLE (-4250 6550);
FORCEADD DNS..1
(-4775 7725);
PAINT RED (-4775 7725);
FORCEPROP 2 LAST CDS_LIB mstr_misc
J 0
(-4775 7725);
DISPLAY INVISIBLE (-4775 7725);
FORCEPROP 1 LAST COMMENT_BODY TRUE
R 1
J 0
(-4700 7500);
DISPLAY 0.872340 (-4700 7500);
PAINT GREEN (-4700 7500);
DISPLAY INVISIBLE (-4700 7500);
FORCEADD DNS..1
(-4475 7725);
PAINT RED (-4475 7725);
FORCEPROP 2 LAST CDS_LIB mstr_misc
J 0
(-4475 7725);
DISPLAY INVISIBLE (-4475 7725);
FORCEPROP 1 LAST COMMENT_BODY TRUE
R 1
J 0
(-4400 7500);
DISPLAY 0.872340 (-4400 7500);
PAINT GREEN (-4400 7500);
DISPLAY INVISIBLE (-4400 7500);
FORCEADD DNS..1
(-4200 7725);
PAINT RED (-4200 7725);
FORCEPROP 2 LAST CDS_LIB mstr_misc
J 0
(-4200 7725);
DISPLAY INVISIBLE (-4200 7725);
FORCEPROP 1 LAST COMMENT_BODY TRUE
R 1
J 0
(-4125 7500);
DISPLAY 0.872340 (-4125 7500);
PAINT GREEN (-4125 7500);
DISPLAY INVISIBLE (-4125 7500);
FORCEADD DNS..1
(-2025 8125);
PAINT RED (-2025 8125);
FORCEPROP 2 LAST CDS_LIB mstr_misc
J 0
(-2025 8125);
DISPLAY INVISIBLE (-2025 8125);
FORCEPROP 1 LAST COMMENT_BODY TRUE
R 1
J 0
(-1950 7900);
DISPLAY 0.872340 (-1950 7900);
PAINT GREEN (-1950 7900);
DISPLAY INVISIBLE (-1950 7900);
FORCEADD DNS..1
(-5075 2925);
PAINT RED (-5075 2925);
FORCEPROP 2 LAST CDS_LIB mstr_misc
J 0
(-5075 2925);
DISPLAY INVISIBLE (-5075 2925);
FORCEPROP 1 LAST COMMENT_BODY TRUE
R 1
J 0
(-5000 2700);
DISPLAY 0.872340 (-5000 2700);
PAINT GREEN (-5000 2700);
DISPLAY INVISIBLE (-5000 2700);
FORCEADD QUANTA_TITLE_BLOCK_C..1
(3250 1750);
FORCEPROP 0 LAST CDS_CON_LAST_MODIFIED Thu Sep 14 16:12:20 2023
J 0
(1365 1765);
DISPLAY INVISIBLE (1365 1765);
FORCEPROP 1 LAST CUSTOM_TXT_CDS <CON_LAST_MODIFIED>
J 0
(1365 1765);
DISPLAY 0.978723 (1365 1765);
FORCEPROP 2 LAST CUSTOM_TXT_CDS <XR_PAGE_TITLE>
J 0
(-4640 7000);
DISPLAY 0.638298 (-4640 7000);
PAINT PINK (-4640 7000);
DISPLAY INVISIBLE (-4640 7000);
FORCEPROP 1 LAST CUSTOM_TXT_CDS <NAME_2>
J 0
(75 1800);
FORCEPROP 1 LAST CUSTOM_TXT_CDS <NAME_1>
J 0
(75 1925);
FORCEPROP 1 LAST CUSTOM_TXT_CDS <Q_NUMBER>
J 0
(1847 1853);
DISPLAY 1.212766 (1847 1853);
FORCEPROP 1 LAST CUSTOM_TXT_CDS <Q_PROJ>
J 0
(868 1852);
DISPLAY 1.212766 (868 1852);
FORCEPROP 1 LAST CUSTOM_TXT_CDS <Q_REV>
J 0
(3066 1853);
DISPLAY 1.212766 (3066 1853);
FORCEPROP 1 LAST CUSTOM_TXT_CDS <CON_PAGE_NUM> OF <CON_TOTAL_PAGES>
J 0
(2804 1768);
DISPLAY 0.978723 (2804 1768);
FORCEPROP 1 LAST Q_TITLE PVDDCR_CPU0_P1/PVDDCR_SOC_P1 VR CONTROLLER
J 0
(-6050 1800);
DISPLAY 2.446809 (-6050 1800);
PAINT GREEN (-6050 1800);
FORCEPROP 2 LAST CDS_XR_PAGE_TITLE CR-210 : @T6G_MB_LIB.T6G(SCH_1):PAGE210
J 0
(-4640 7000);
DISPLAY 0.638298 (-4640 7000);
PAINT PINK (-4640 7000);
DISPLAY INVISIBLE (-4640 7000);
FORCEPROP 2 LAST CDS_LIB pure_quanta
J 0
(3250 1750);
DISPLAY INVISIBLE (3250 1750);
FORCEPROP 1 LAST CDS_LMAN_SYM_OUTLINE -9475,6775,100,-125
J 0
(3250 1750);
DISPLAY 0.468085 (3250 1750);
PAINT GREEN (3250 1750);
DISPLAY INVISIBLE (3250 1750);
FORCEPROP 2 LAST PAGE_BORDER TRUE
J 0
(-4640 7000);
DISPLAY 0.638298 (-4640 7000);
PAINT PINK (-4640 7000);
DISPLAY INVISIBLE (-4640 7000);
FORCEPROP 1 LAST Q_DEPT BU9
J 1
(-513 1799);
DISPLAY 1.957447 (-513 1799);
PAINT GREEN (-513 1799);
DISPLAY INVISIBLE (-513 1799);
FORCEPROP 1 LAST COMMENT_BODY TRUE
J 0
(3262 1737);
DISPLAY 0.978723 (3262 1737);
PAINT GREEN (3262 1737);
DISPLAY INVISIBLE (3262 1737);
FORCEADD DNS..1
(-4600 6775);
PAINT RED (-4600 6775);
FORCEPROP 2 LAST CDS_LIB mstr_misc
J 0
(-4600 6775);
DISPLAY INVISIBLE (-4600 6775);
FORCEPROP 1 LAST COMMENT_BODY TRUE
R 1
J 0
(-4525 6550);
DISPLAY 0.872340 (-4525 6550);
PAINT GREEN (-4525 6550);
DISPLAY INVISIBLE (-4525 6550);
WIRE 16 -1 (-25 7325)(-25 7250);
WIRE 16 -1 (-25 7800)(-25 7700);
WIRE 16 -1 (300 7250)(300 7325);
WIRE 16 -1 (325 7700)(325 7800);
WIRE 16 -1 (-4000 2900)(-4150 2900);
WIRE 16 -1 (-3125 6150)(-3125 6100);
WIRE 16 -1 (-3700 7950)(-3850 7950);
WIRE 16 -1 (-3725 2325)(-3725 2225);
WIRE 16 -1 (-3250 2325)(-3250 2225);
WIRE 16 -1 (-5300 6700)(-5300 6600);
WIRE 16 -1 (-3875 4200)(-3875 4150);
WIRE 16 -1 (-3875 5000)(-3875 5025);
WIRE 16 -1 (-3875 5300)(-3875 5250);
WIRE 16 -1 (-2400 2125)(-2400 2075);
WIRE 16 -1 (-5025 6700)(-5025 6600);
WIRE 16 -1 (-2075 2150)(-2075 2075);
WIRE 16 -1 (-2350 3500)(-2100 3500);
WIRE 16 -1 (-4825 6700)(-4825 6600);
WIRE 16 -1 (-4600 6700)(-4600 6600);
WIRE 16 -1 (-4325 6700)(-4325 6600);
WIRE 16 -1 (-3875 6125)(-3875 6175);
WIRE 16 -1 (-150 2375)(-150 2250);
WIRE 16 -1 (475 2600)(475 2700);
WIRE 17 273 (-4825 6050)(-3975 6050);
WIRE 17 273 (-4825 6050)(-4825 5240);
WIRE 17 273 (-3975 6050)(-3975 5240);
WIRE 17 273 (-4825 5240)(-3975 5240);
WIRE 16 -1 (-1775 5575)(-2525 5575);
WIRE 16 -1 (-2525 5600)(-2525 5575);
WIRE 16 -1 (-2525 5575)(-3875 5575);
WIRE 16 -1 (-3875 5500)(-3875 5575);
WIRE 16 -1 (-4575 5575)(-3875 5575);
FORCEPROP 2 LAST SIG_NAME VSENSE_VSS_SENSE_A_P1
J 2
(-4085 5585);
DISPLAY 0.489362 (-4085 5585);
WIRE 16 -1 (-425 5975)(375 5975);
FORCEPROP 2 LAST SIG_NAME PVDDCR_CPU0_P1_PWM4
J 2
(190 5985);
DISPLAY 0.489362 (190 5985);
WIRE 16 -1 (-425 5875)(375 5875);
FORCEPROP 2 LAST SIG_NAME PVDDCR_CPU0_P1_IMON4
J 2
(215 5885);
DISPLAY 0.489362 (215 5885);
WIRE 17 273 (1550 5775)(3150 5775);
WIRE 17 273 (1550 6975)(1550 5775);
WIRE 17 273 (3150 6975)(3150 5775);
WIRE 17 273 (1550 6975)(3150 6975);
WIRE 17 273 (1550 8350)(3150 8350);
WIRE 17 273 (1550 8350)(1550 7050);
WIRE 17 273 (3150 8350)(3150 7050);
WIRE 17 273 (1550 7050)(3150 7050);
WIRE 16 -1 (725 4300)(725 4375);
WIRE 16 -1 (725 4375)(500 4375);
WIRE 16 -1 (725 4600)(725 4675);
WIRE 16 -1 (725 4675)(500 4675);
WIRE 16 -1 (725 4900)(725 4975);
WIRE 16 -1 (725 4975)(500 4975);
WIRE 16 -1 (-5125 7850)(-5125 7950);
WIRE 16 -1 (-4775 7950)(-5125 7950);
WIRE 16 -1 (-5125 8000)(-5125 7950);
WIRE 16 -1 (-4475 7950)(-4775 7950);
WIRE 16 -1 (-4775 7850)(-4775 7950);
WIRE 16 -1 (-4200 7950)(-4475 7950);
WIRE 16 -1 (-4475 7850)(-4475 7950);
WIRE 16 -1 (-4200 7950)(-4200 7850);
WIRE 16 -1 (-5075 2850)(-5075 2825);
WIRE 16 -1 (-5075 2825)(-4850 2825);
FORCEPROP 0 LAST VOLTAGE 0
J 0
(-5037 2825);
DISPLAY INVISIBLE (-5037 2825);
WIRE 16 -1 (-4850 2850)(-4850 2825);
WIRE 16 -1 (-4850 2825)(-4850 2775);
WIRE 16 -1 (1175 8100)(1175 8050);
WIRE 16 -1 (1175 8050)(850 8050);
WIRE 16 -1 (-4325 2600)(-4125 2600);
WIRE 16 -1 (-4325 2675)(-4325 2600);
WIRE 16 -1 (-2975 2425)(-2825 2425);
WIRE 16 -1 (-2975 2450)(-2975 2425);
WIRE 16 -1 (-3875 3050)(-3875 3025);
WIRE 16 -1 (-3875 3000)(-3875 3025);
WIRE 16 -1 (-4550 3025)(-3875 3025);
WIRE 16 -1 (-4550 3025)(-4550 3100);
WIRE 16 -1 (-3375 3125)(-3375 3025);
WIRE 16 -1 (-3375 3025)(-3200 3025);
WIRE 16 -1 (-2275 3750)(-2850 3750);
WIRE 16 -1 (-2850 3750)(-2850 3625);
WIRE 16 -1 (-1775 3625)(-2850 3625);
WIRE 16 -1 (-2850 3500)(-2850 3625);
WIRE 16 -1 (-2550 3500)(-2850 3500);
WIRE 16 -1 (-2850 3500)(-3000 3500);
WIRE 16 -1 (-3000 3500)(-3000 3525);
WIRE 16 -1 (-3875 3925)(-3875 4000);
WIRE 16 -1 (-3875 4000)(-4550 4000);
WIRE 16 -1 (-4550 3950)(-4550 4000);
WIRE 16 -1 (-4550 4000)(-4550 4025);
WIRE 16 -1 (-3300 4175)(-2950 4175);
WIRE 16 -1 (-3300 4250)(-3300 4175);
WIRE 16 -1 (-2100 2950)(-2100 3025);
WIRE 16 -1 (-2100 3025)(-2325 3025);
WIRE 16 -1 (-1875 2325)(-1775 2325);
WIRE 16 -1 (-1875 2275)(-1875 2325);
WIRE 16 -1 (-3300 8225)(-3300 8150);
WIRE 16 -1 (-3300 8150)(-3000 8150);
WIRE 16 -1 (-1775 7575)(-1775 7600);
WIRE 16 -1 (-1775 7600)(-1900 7600);
WIRE 16 -1 (-1775 8125)(-1775 8150);
WIRE 16 -1 (-1775 8150)(-1925 8150);
WIRE 16 -1 (-3475 6575)(-2800 6575);
FORCEPROP 2 LAST SIG_NAME SMB_VR_3V3STBY_SDA
J 0
(-3485 6585);
DISPLAY 0.489362 (-3485 6585);
WIRE 16 -1 (-425 6775)(375 6775);
FORCEPROP 2 LAST SIG_NAME PVDDCR_CPU0_P1_IMON1
J 2
(215 6785);
DISPLAY 0.489362 (215 6785);
WIRE 16 -1 (-425 7875)(-150 7875);
WIRE 16 -1 (-150 7875)(-150 8050);
WIRE 16 -1 (-150 8050)(-25 8050);
WIRE 16 -1 (-25 8050)(325 8050);
FORCEPROP 2 LAST SIG_NAME PVDDCR_CPU0_P1_VCC
J 2
(290 8060);
DISPLAY 0.489362 (290 8060);
FORCEPROP 2 LASTPROP $XRERR UNIQUE?
J 0
(50 8060);
DISPLAY 0.638298 (50 8060);
PAINT MONO (50 8060);
DISPLAY INVISIBLE (50 8060);
WIRE 16 -1 (-25 8050)(-25 8000);
WIRE 16 -1 (650 8050)(325 8050);
WIRE 16 -1 (325 8000)(325 8050);
WIRE 16 -1 (-1775 6975)(-2700 6975);
FORCEPROP 2 LAST SIG_NAME SVID_PVDDCR_CPU0_P1_SVTI_R
J 0
(-2485 6985);
DISPLAY 0.489362 (-2485 6985);
FORCEPROP 2 LASTPROP $XRERR UNIQUE?
J 0
(-2725 6985);
DISPLAY 0.638298 (-2725 6985);
PAINT MONO (-2725 6985);
DISPLAY INVISIBLE (-2725 6985);
WIRE 16 -1 (-2600 6725)(-1775 6725);
FORCEPROP 2 LAST SIG_NAME PVDDCR_CPU0_P1_PMSCL_R
J 2
(-1910 6735);
DISPLAY 0.489362 (-1910 6735);
FORCEPROP 2 LASTPROP $XRERR UNIQUE?
J 0
(-2150 6735);
DISPLAY 0.638298 (-2150 6735);
PAINT MONO (-2150 6735);
DISPLAY INVISIBLE (-2150 6735);
WIRE 16 -1 (-2700 7425)(-1775 7425);
FORCEPROP 2 LAST SIG_NAME SVID_PVDDCR_CPU0_P1_SVC_R1
J 0
(-2535 7435);
DISPLAY 0.553191 (-2535 7435);
FORCEPROP 2 LASTPROP $XRERR UNIQUE?
J 0
(-2775 7435);
DISPLAY 0.638298 (-2775 7435);
PAINT MONO (-2775 7435);
DISPLAY INVISIBLE (-2775 7435);
WIRE 16 -1 (-425 5275)(375 5275);
FORCEPROP 2 LAST SIG_NAME PVDDCR_CPU0_P1_IMON6
J 2
(215 5285);
DISPLAY 0.489362 (215 5285);
WIRE 16 -1 (-1775 7125)(-2700 7125);
FORCEPROP 2 LAST SIG_NAME SVID_PVDDCR_CPU0_P1_SVTO_R
J 0
(-2485 7135);
DISPLAY 0.489362 (-2485 7135);
FORCEPROP 2 LASTPROP $XRERR UNIQUE?
J 0
(-2725 7135);
DISPLAY 0.638298 (-2725 7135);
PAINT MONO (-2725 7135);
DISPLAY INVISIBLE (-2725 7135);
WIRE 16 -1 (-2750 4175)(-2650 4175);
WIRE 16 -1 (-2650 4175)(-2650 4025);
WIRE 16 -1 (-1775 4025)(-2650 4025);
FORCEPROP 2 LAST SIG_NAME PVDDCR_CPU0_P1_RESET_N_R
J 0
(-2485 4035);
DISPLAY 0.489362 (-2485 4035);
FORCEPROP 2 LASTPROP $XRERR UNIQUE?
J 0
(-2725 4035);
DISPLAY 0.638298 (-2725 4035);
PAINT MONO (-2725 4035);
DISPLAY INVISIBLE (-2725 4035);
WIRE 16 -1 (-2725 4025)(-2650 4025);
WIRE 16 -1 (-425 4975)(300 4975);
FORCEPROP 2 LAST SIG_NAME NC_PVDDCR_CPU0_P1_IMON7
J 2
(240 4985);
DISPLAY 0.489362 (240 4985);
FORCEPROP 2 LASTPROP $XRERR UNIQUE?
J 0
(0 4985);
DISPLAY 0.638298 (0 4985);
PAINT MONO (0 4985);
DISPLAY INVISIBLE (0 4985);
WIRE 16 -1 (-425 4675)(300 4675);
FORCEPROP 2 LAST SIG_NAME NC_PVDDCR_CPU0_P1_IMON8
J 2
(240 4685);
DISPLAY 0.489362 (240 4685);
FORCEPROP 2 LASTPROP $XRERR UNIQUE?
J 0
(0 4685);
DISPLAY 0.638298 (0 4685);
PAINT MONO (0 4685);
DISPLAY INVISIBLE (0 4685);
WIRE 16 -1 (-1775 2625)(-2100 2625);
WIRE 16 -1 (-2100 2625)(-2100 2775);
WIRE 16 -1 (-2825 2775)(-2100 2775);
FORCEPROP 2 LAST SIG_NAME PWRGD_PVDDCR_SOC_P1_R
J 2
(-2260 2785);
DISPLAY 0.489362 (-2260 2785);
FORCEPROP 2 LASTPROP $XRERR UNIQUE?
J 0
(-2500 2785);
DISPLAY 0.638298 (-2500 2785);
PAINT MONO (-2500 2785);
DISPLAY INVISIBLE (-2500 2785);
WIRE 16 -1 (-2825 3025)(-2825 2775);
WIRE 16 -1 (-2825 2775)(-3000 2775);
WIRE 16 -1 (-2825 3025)(-2525 3025);
WIRE 16 -1 (-3000 3025)(-2825 3025);
WIRE 16 -1 (-2700 7275)(-1775 7275);
FORCEPROP 2 LAST SIG_NAME SVID_PVDDCR_CPU0_P1_SVD_R1
J 0
(-2560 7285);
DISPLAY 0.553191 (-2560 7285);
FORCEPROP 2 LASTPROP $XRERR UNIQUE?
J 0
(-2800 7285);
DISPLAY 0.638298 (-2800 7285);
PAINT MONO (-2800 7285);
DISPLAY INVISIBLE (-2800 7285);
WIRE 16 -1 (-2600 6425)(-1775 6425);
FORCEPROP 2 LAST SIG_NAME PVDDCR_CPU0_P1_PMALERT_R
J 2
(-1860 6435);
DISPLAY 0.489362 (-1860 6435);
FORCEPROP 2 LASTPROP $XRERR UNIQUE?
J 0
(-2100 6435);
DISPLAY 0.638298 (-2100 6435);
PAINT MONO (-2100 6435);
DISPLAY INVISIBLE (-2100 6435);
WIRE 16 -1 (-2575 7725)(-2400 7725);
WIRE 16 -1 (-2400 7725)(-1775 7725);
FORCEPROP 2 LAST SIG_NAME PVDDCR_CPU0_P1_EN_R
J 2
(-1885 7735);
DISPLAY 0.489362 (-1885 7735);
FORCEPROP 2 LASTPROP $XRERR UNIQUE?
J 0
(-2125 7735);
DISPLAY 0.638298 (-2125 7735);
PAINT MONO (-2125 7735);
DISPLAY INVISIBLE (-2125 7735);
WIRE 16 -1 (-2400 7600)(-2400 7725);
WIRE 16 -1 (-2100 7600)(-2400 7600);
WIRE 16 -1 (-2600 6575)(-1775 6575);
FORCEPROP 2 LAST SIG_NAME PVDDCR_CPU0_P1_PMSDA_R
J 2
(-1910 6585);
DISPLAY 0.489362 (-1910 6585);
FORCEPROP 2 LASTPROP $XRERR UNIQUE?
J 0
(-2150 6585);
DISPLAY 0.638298 (-2150 6585);
PAINT MONO (-2150 6585);
DISPLAY INVISIBLE (-2150 6585);
WIRE 16 -1 (-425 4775)(300 4775);
FORCEPROP 2 LAST SIG_NAME NC_PVDDCR_CPU0_P1_PWM8
J 2
(215 4785);
DISPLAY 0.489362 (215 4785);
FORCEPROP 2 LASTPROP $XRERR UNIQUE?
J 0
(330 4775);
DISPLAY 0.638298 (330 4775);
PAINT MONO (330 4775);
DISPLAY INVISIBLE (330 4775);
WIRE 16 -1 (-425 5075)(300 5075);
FORCEPROP 2 LAST SIG_NAME NC_PVDDCR_CPU0_P1_PWM7
J 2
(215 5085);
DISPLAY 0.489362 (215 5085);
FORCEPROP 2 LASTPROP $XRERR UNIQUE?
J 0
(330 5075);
DISPLAY 0.638298 (330 5075);
PAINT MONO (330 5075);
DISPLAY INVISIBLE (330 5075);
WIRE 16 -1 (-2700 5825)(-2525 5825);
WIRE 16 -1 (-1775 5825)(-2525 5825);
FORCEPROP 2 LAST SIG_NAME VSENSE_PVDDCR_CPU0_P1_VSEN0
J 2
(-1885 5835);
DISPLAY 0.489362 (-1885 5835);
FORCEPROP 2 LASTPROP $XRERR UNIQUE?
J 0
(-2125 5835);
DISPLAY 0.638298 (-2125 5835);
PAINT MONO (-2125 5835);
DISPLAY INVISIBLE (-2125 5835);
WIRE 16 -1 (-2525 5800)(-2525 5825);
WIRE 16 -1 (-425 3875)(400 3875);
FORCEPROP 2 LAST SIG_NAME PVDDCR_SOC_P1_PWM2
J 2
(165 3885);
DISPLAY 0.489362 (165 3885);
WIRE 16 -1 (-2800 8150)(-2425 8150);
WIRE 16 -1 (-2425 8150)(-2125 8150);
WIRE 16 -1 (-2425 8150)(-2425 7875);
WIRE 16 -1 (-1775 7875)(-2425 7875);
FORCEPROP 2 LAST SIG_NAME PWRGD_PVDDCR_CPU0_P1_R
J 2
(-1885 7885);
DISPLAY 0.489362 (-1885 7885);
FORCEPROP 2 LASTPROP $XRERR UNIQUE?
J 0
(-2125 7885);
DISPLAY 0.638298 (-2125 7885);
PAINT MONO (-2125 7885);
DISPLAY INVISIBLE (-2125 7885);
WIRE 16 -1 (-2425 7875)(-2575 7875);
WIRE 16 -1 (-425 5375)(375 5375);
FORCEPROP 2 LAST SIG_NAME PVDDCR_CPU0_P1_PWM6
J 2
(190 5385);
DISPLAY 0.489362 (190 5385);
WIRE 16 -1 (300 7575)(700 7575);
FORCEPROP 2 LAST SIG_NAME PVDDCR_CPU0_P1_VCCS
J 2
(690 7585);
DISPLAY 0.489362 (690 7585);
WIRE 16 -1 (300 7525)(300 7575);
WIRE 16 -1 (300 7575)(-25 7575);
WIRE 16 -1 (-25 7575)(-25 7525);
WIRE 16 -1 (-25 7575)(-425 7575);
WIRE 16 -1 (-3725 2525)(-3725 2600);
WIRE 16 -1 (-3725 2600)(-3250 2600);
WIRE 16 -1 (-3925 2600)(-3725 2600);
WIRE 16 -1 (-2400 2600)(-3250 2600);
WIRE 16 -1 (-3250 2525)(-3250 2600);
WIRE 16 -1 (-2400 2600)(-2400 2525);
WIRE 16 -1 (-2400 2525)(-1775 2525);
FORCEPROP 2 LAST SIG_NAME PVDDCR_CPU0_P1_VMON
J 2
(-1910 2535);
DISPLAY 0.489362 (-1910 2535);
FORCEPROP 2 LASTPROP $XRERR UNIQUE?
J 0
(-2150 2535);
DISPLAY 0.638298 (-2150 2535);
PAINT MONO (-2150 2535);
DISPLAY INVISIBLE (-2150 2535);
WIRE 16 -1 (-2625 2425)(-2400 2425);
WIRE 16 -1 (-2400 2425)(-2075 2425);
WIRE 16 -1 (-2400 2325)(-2400 2425);
WIRE 16 -1 (-1775 2425)(-2075 2425);
FORCEPROP 2 LAST SIG_NAME PVDDCR_CPU0_P1_VINSEN
J 2
(-1885 2435);
DISPLAY 0.489362 (-1885 2435);
FORCEPROP 2 LASTPROP $XRERR UNIQUE?
J 0
(-2125 2435);
DISPLAY 0.638298 (-2125 2435);
PAINT MONO (-2125 2435);
DISPLAY INVISIBLE (-2125 2435);
WIRE 16 -1 (-2075 2350)(-2075 2425);
WIRE 16 -1 (125 2675)(-150 2675);
FORCEPROP 2 LAST SIG_NAME PVDDCR_CPU0_P1_TEMP0
J 2
(115 2685);
DISPLAY 0.489362 (115 2685);
WIRE 16 -1 (-150 2575)(-150 2675);
WIRE 16 -1 (-150 2675)(-425 2675);
WIRE 16 -1 (-2450 4700)(-2450 4725);
WIRE 16 -1 (-2450 4725)(-1775 4725);
FORCEPROP 2 LAST SIG_NAME VSENSE_PVDDCR_SOC_P1_VSEN1
J 2
(-1885 4735);
DISPLAY 0.489362 (-1885 4735);
FORCEPROP 2 LASTPROP $XRERR UNIQUE?
J 0
(-2125 4735);
DISPLAY 0.638298 (-2125 4735);
PAINT MONO (-2125 4735);
DISPLAY INVISIBLE (-2125 4735);
WIRE 16 -1 (-2625 4725)(-2450 4725);
WIRE 16 -1 (-2450 4500)(-2450 4475);
WIRE 16 -1 (-2450 4475)(-1775 4475);
WIRE 16 -1 (-2450 4475)(-3875 4475);
WIRE 16 -1 (-3875 4400)(-3875 4475);
WIRE 16 -1 (-4575 4475)(-3875 4475);
FORCEPROP 2 LAST SIG_NAME VSENSE_VSS_SENSE_A_P1
J 2
(-4085 4485);
DISPLAY 0.489362 (-4085 4485);
WIRE 16 -1 (-425 3775)(400 3775);
FORCEPROP 2 LAST SIG_NAME PVDDCR_SOC_P1_IMON2
J 2
(190 3785);
DISPLAY 0.489362 (190 3785);
WIRE 16 -1 (-425 6875)(375 6875);
FORCEPROP 2 LAST SIG_NAME PVDDCR_CPU0_P1_PWM1
J 2
(190 6885);
DISPLAY 0.489362 (190 6885);
WIRE 16 -1 (-425 4475)(300 4475);
FORCEPROP 2 LAST SIG_NAME NC_PVDDCR_CPU0_P1_PWM9
J 2
(215 4485);
DISPLAY 0.489362 (215 4485);
FORCEPROP 2 LASTPROP $XRERR UNIQUE?
J 0
(330 4475);
DISPLAY 0.638298 (330 4475);
PAINT MONO (330 4475);
DISPLAY INVISIBLE (330 4475);
WIRE 16 -1 (-425 4375)(300 4375);
FORCEPROP 2 LAST SIG_NAME NC_PVDDCR_CPU0_P1_IMON9
J 2
(240 4385);
DISPLAY 0.489362 (240 4385);
FORCEPROP 2 LASTPROP $XRERR UNIQUE?
J 0
(0 4385);
DISPLAY 0.638298 (0 4385);
PAINT MONO (0 4385);
DISPLAY INVISIBLE (0 4385);
WIRE 16 -1 (-425 4175)(400 4175);
FORCEPROP 2 LAST SIG_NAME PVDDCR_SOC_P1_PWM3
J 2
(165 4185);
DISPLAY 0.489362 (165 4185);
WIRE 16 -1 (-425 4075)(400 4075);
FORCEPROP 2 LAST SIG_NAME PVDDCR_SOC_P1_IMON3
J 2
(190 4085);
DISPLAY 0.489362 (190 4085);
WIRE 16 -1 (-2075 3750)(-1925 3750);
WIRE 16 -1 (-1925 3750)(-1925 3875);
WIRE 16 -1 (-1775 3875)(-1925 3875);
WIRE 16 -1 (-2725 3875)(-1925 3875);
FORCEPROP 2 LAST SIG_NAME PVDDCR_CPU0_P1_OCP_N_R
J 0
(-2460 3885);
DISPLAY 0.489362 (-2460 3885);
FORCEPROP 2 LASTPROP $XRERR UNIQUE?
J 0
(-2700 3885);
DISPLAY 0.638298 (-2700 3885);
PAINT MONO (-2700 3885);
DISPLAY INVISIBLE (-2700 3885);
WIRE 16 -1 (-3875 3325)(-3875 3275);
WIRE 16 -1 (-3875 3275)(-2600 3275);
WIRE 16 -1 (-3875 3275)(-3875 3250);
WIRE 16 -1 (-2600 3275)(-2600 3125);
WIRE 16 -1 (-2600 3125)(-1775 3125);
FORCEPROP 2 LAST SIG_NAME PVDDCR_SOC_P1_EN//ADDR_CFG
J 2
(-1885 3135);
DISPLAY 0.489362 (-1885 3135);
FORCEPROP 2 LASTPROP $XRERR UNIQUE?
J 0
(-2125 3135);
DISPLAY 0.638298 (-2125 3135);
PAINT MONO (-2125 3135);
DISPLAY INVISIBLE (-2125 3135);
WIRE 16 -1 (475 2975)(700 2975);
WIRE 16 -1 (475 2900)(475 2975);
WIRE 16 -1 (475 2975)(-425 2975);
FORCEPROP 2 LAST SIG_NAME PVDDCR_SOC_P1_TEMP1
J 2
(165 2985);
DISPLAY 0.489362 (165 2985);
WIRE 16 -1 (-425 3575)(375 3575);
FORCEPROP 2 LAST SIG_NAME PVDDCR_SOC_P1_PWM1
J 2
(165 3585);
DISPLAY 0.489362 (165 3585);
WIRE 16 -1 (-425 3475)(375 3475);
FORCEPROP 2 LAST SIG_NAME PVDDCR_SOC_P1_IMON1
J 2
(190 3485);
DISPLAY 0.489362 (190 3485);
WIRE 16 -1 (-425 5675)(375 5675);
FORCEPROP 2 LAST SIG_NAME PVDDCR_CPU0_P1_PWM5
J 2
(190 5685);
DISPLAY 0.489362 (190 5685);
WIRE 16 -1 (-425 5575)(375 5575);
FORCEPROP 2 LAST SIG_NAME PVDDCR_CPU0_P1_IMON5
J 2
(215 5585);
DISPLAY 0.489362 (215 5585);
WIRE 16 -1 (-425 6275)(400 6275);
FORCEPROP 2 LAST SIG_NAME PVDDCR_CPU0_P1_PWM3
J 2
(215 6285);
DISPLAY 0.489362 (215 6285);
WIRE 16 -1 (-425 6175)(400 6175);
FORCEPROP 2 LAST SIG_NAME PVDDCR_CPU0_P1_IMON3
J 2
(240 6185);
DISPLAY 0.489362 (240 6185);
WIRE 16 -1 (-425 6575)(400 6575);
FORCEPROP 2 LAST SIG_NAME PVDDCR_CPU0_P1_PWM2
J 2
(190 6585);
DISPLAY 0.489362 (190 6585);
WIRE 16 -1 (-425 6475)(400 6475);
FORCEPROP 2 LAST SIG_NAME PVDDCR_CPU0_P1_IMON2
J 2
(215 6485);
DISPLAY 0.489362 (215 6485);
WIRE 16 -1 (-5625 7125)(-5025 7125);
WIRE 16 -1 (-4825 7125)(-5025 7125);
WIRE 16 -1 (-5025 7125)(-5025 6900);
WIRE 16 -1 (-4775 7125)(-4825 7125);
WIRE 16 -1 (-4825 6900)(-4825 7125);
WIRE 16 -1 (-2900 7125)(-4775 7125);
FORCEPROP 2 LAST SIG_NAME SVID_PVDDCR_CPU0_P1_SVTO
J 0
(-3860 7135);
DISPLAY 0.489362 (-3860 7135);
WIRE 16 -1 (-4775 7650)(-4775 7125);
WIRE 16 -1 (-2775 7725)(-3350 7725);
FORCEPROP 2 LAST SIG_NAME PVDDCR_CPU0_P1_EN
J 2
(-2960 7735);
DISPLAY 0.489362 (-2960 7735);
WIRE 16 -1 (-5625 7275)(-4600 7275);
WIRE 16 -1 (-4475 7275)(-4600 7275);
WIRE 16 -1 (-4600 6900)(-4600 7275);
WIRE 16 -1 (-4475 7275)(-2900 7275);
FORCEPROP 2 LAST SIG_NAME SVID_PVDDCR_CPU0_P1_SVD_R
J 0
(-3985 7285);
DISPLAY 0.489362 (-3985 7285);
WIRE 16 -1 (-4475 7650)(-4475 7275);
WIRE 16 -1 (-2900 7425)(-4200 7425);
FORCEPROP 2 LAST SIG_NAME SVID_PVDDCR_CPU0_P1_SVC_R
J 0
(-3985 7435);
DISPLAY 0.489362 (-3985 7435);
WIRE 16 -1 (-4200 7650)(-4200 7425);
WIRE 16 -1 (-4200 7425)(-4325 7425);
WIRE 16 -1 (-4325 6900)(-4325 7425);
WIRE 16 -1 (-4325 7425)(-5625 7425);
WIRE 16 -1 (-3350 7875)(-3125 7875);
WIRE 16 -1 (-3125 7875)(-2775 7875);
FORCEPROP 2 LAST SIG_NAME PWRGD_PVDDCR_CPU0_P1
J 2
(-2885 7885);
DISPLAY 0.489362 (-2885 7885);
WIRE 16 -1 (-3125 7950)(-3125 7875);
WIRE 16 -1 (-3125 7950)(-3500 7950);
WIRE 16 -1 (-5300 6975)(-5125 6975);
WIRE 16 -1 (-5300 6975)(-5300 6900);
WIRE 16 -1 (-2900 6975)(-5125 6975);
FORCEPROP 2 LAST SIG_NAME SVID_PVDDCR_CPU0_P1_SVTI
J 0
(-3860 7000);
DISPLAY 0.489362 (-3860 7000);
FORCEPROP 2 LASTPROP $XRERR UNIQUE?
J 0
(-4100 7000);
DISPLAY 0.638298 (-4100 7000);
PAINT MONO (-4100 7000);
DISPLAY INVISIBLE (-4100 7000);
WIRE 16 -1 (-5125 7650)(-5125 6975);
WIRE 16 -1 (-3875 4800)(-3875 4725);
WIRE 16 -1 (-2825 4725)(-3875 4725);
WIRE 16 -1 (-4575 4725)(-3875 4725);
FORCEPROP 2 LAST SIG_NAME VSENSE_PVDDCR_SOC_P1_DP
J 2
(-4035 4735);
DISPLAY 0.489362 (-4035 4735);
WIRE 17 273 (-4825 4975)(-3975 4975);
WIRE 17 273 (-4825 4975)(-4825 4165);
WIRE 17 273 (-3975 4975)(-3975 4165);
WIRE 17 273 (-4825 4165)(-3975 4165);
WIRE 16 -1 (-3450 4025)(-2925 4025);
FORCEPROP 2 LAST SIG_NAME PVDDCR_CPU0_P1_RESET_N
J 0
(-3435 4035);
DISPLAY 0.489362 (-3435 4035);
WIRE 17 273 (-5950 2375)(-4750 2375);
WIRE 17 273 (-5950 2375)(-5950 1975);
WIRE 17 273 (-4750 2375)(-4750 1975);
WIRE 17 273 (-5950 1975)(-4750 1975);
WIRE 16 -1 (-5275 3200)(-5075 3200);
WIRE 16 -1 (-5075 3200)(-4850 3200);
WIRE 16 -1 (-5075 3200)(-5075 3050);
WIRE 16 -1 (-4700 3200)(-4850 3200);
FORCEPROP 2 LAST SIG_NAME PVDDCR_SOC_P1_EN_RC
J 2
(-4735 3210);
DISPLAY 0.489362 (-4735 3210);
FORCEPROP 2 LASTPROP $XRERR UNIQUE?
J 0
(-4975 3210);
DISPLAY 0.638298 (-4975 3210);
PAINT MONO (-4975 3210);
DISPLAY INVISIBLE (-4975 3210);
WIRE 16 -1 (-4850 3050)(-4850 3200);
WIRE 16 -1 (-4550 3400)(-4550 3625);
WIRE 16 -1 (-4175 3625)(-4550 3625);
FORCEPROP 2 LAST SIG_NAME PVDDCR_SOC_P1_EN_GD
J 2
(-4085 3575);
DISPLAY 0.489362 (-4085 3575);
FORCEPROP 2 LASTPROP $XRERR UNIQUE?
J 0
(-4325 3575);
DISPLAY 0.638298 (-4325 3575);
PAINT MONO (-4325 3575);
DISPLAY INVISIBLE (-4325 3575);
WIRE 16 -1 (-4550 3750)(-4550 3625);
WIRE 16 -1 (-2800 6425)(-3125 6425);
WIRE 16 -1 (-3125 6350)(-3125 6425);
WIRE 16 -1 (-3125 6425)(-3475 6425);
FORCEPROP 2 LAST SIG_NAME PVDDCR_CPU0_P1_PMALERT
J 0
(-3475 6435);
DISPLAY 0.489362 (-3475 6435);
WIRE 16 -1 (-3475 6725)(-2800 6725);
FORCEPROP 2 LAST SIG_NAME SMB_VR_3V3STBY_SCL
J 0
(-3475 6735);
DISPLAY 0.489362 (-3475 6735);
WIRE 16 -1 (-5475 3200)(-5900 3200);
FORCEPROP 2 LAST SIG_NAME PVDDCR_SOC_P1_EN
J 2
(-5560 3210);
DISPLAY 0.489362 (-5560 3210);
WIRE 16 -1 (-3200 2775)(-3425 2775);
FORCEPROP 2 LAST SIG_NAME PWRGD_PVDDCR_SOC_P1
J 2
(-3335 2785);
DISPLAY 0.489362 (-3335 2785);
WIRE 16 -1 (-3425 2775)(-3425 2900);
WIRE 16 -1 (-3425 2775)(-3875 2775);
WIRE 16 -1 (-3425 2900)(-3800 2900);
WIRE 16 -1 (-3875 5925)(-3875 5825);
WIRE 16 -1 (-2900 5825)(-3875 5825);
WIRE 16 -1 (-4575 5825)(-3875 5825);
FORCEPROP 2 LAST SIG_NAME VSENSE_PVDDCR_CPU0_P1_DP
J 2
(-4010 5835);
DISPLAY 0.489362 (-4010 5835);
WIRE 16 -1 (-3450 3875)(-2925 3875);
FORCEPROP 2 LAST SIG_NAME PVDDCR_CPU0_P1_OCP_N
J 0
(-3435 3885);
DISPLAY 0.489362 (-3435 3885);
CIRCLE (-2825 5750)(-2665 5750);
PAINT YELLOW (-2825 5750);
DOT 1 (-4200 7425);
DOT 1 (-150 2675);
CIRCLE (-2775 4775)(-2615 4775);
PAINT YELLOW (-2775 4775);
DOT 1 (-3875 3275);
DOT 1 (-4850 2825);
DOT 1 (-5075 3200);
DOT 1 (-2825 2775);
DOT 1 (-3250 2600);
DOT 1 (-5125 6975);
DOT 1 (-5025 7125);
DOT 1 (-5125 7950);
DOT 1 (-4550 3625);
DOT 1 (-3875 3025);
DOT 1 (-4550 4000);
DOT 1 (-3875 4725);
DOT 1 (-3875 5575);
DOT 1 (-3875 5825);
DOT 1 (-2400 2425);
DOT 1 (-2075 2425);
DOT 1 (-2825 3025);
DOT 1 (-2850 3500);
DOT 1 (-2850 3625);
DOT 1 (-2650 4025);
DOT 1 (-2450 4475);
DOT 1 (-2450 4725);
DOT 1 (-1925 3875);
DOT 1 (-2525 5575);
DOT 1 (-2525 5825);
DOT 1 (-4825 7125);
DOT 1 (-4775 7125);
DOT 1 (-4600 7275);
DOT 1 (-4325 7425);
DOT 1 (-2425 7875);
DOT 1 (-2425 8150);
DOT 1 (475 2975);
DOT 1 (-25 7575);
DOT 1 (300 7575);
DOT 1 (-25 8050);
DOT 1 (325 8050);
DOT 1 (-4475 7950);
DOT 1 (-4775 7950);
DOT 1 (-3875 4475);
DOT 1 (-3425 2775);
DOT 1 (-3725 2600);
DOT 1 (-3125 6425);
DOT 1 (-4850 3200);
CIRCLE (-5375 6775)(-5215 6775);
PAINT YELLOW (-5375 6775);
DOT 1 (-2400 7725);
DOT 1 (-3125 7875);
DOT 1 (-4475 7275);
FORCENOTE
PMBUS ADDRESS AND CONFIG
(-5975 2425) 0;
DISPLAY LEFT (-5975 2425);
DISPLAY 1.170213 (-5975 2425);
PAINT WHITE (-5975 2425);
FORCENOTE
CONFIG/R
(-5075 2300) 0;
DISPLAY LEFT (-5075 2300);
DISPLAY 0.808511 (-5075 2300);
PAINT WHITE (-5075 2300);
FORCENOTE
ADDRESS(7-BIT)
(-5650 2300) 0;
DISPLAY LEFT (-5650 2300);
DISPLAY 0.808511 (-5650 2300);
PAINT WHITE (-5650 2300);
FORCENOTE
0X72
(-5425 2200) 0;
DISPLAY LEFT (-5425 2200);
DISPLAY 0.638298 (-5425 2200);
PAINT WHITE (-5425 2200);
FORCENOTE
0X4D
(-5425 2050) 0;
DISPLAY LEFT (-5425 2050);
DISPLAY 0.638298 (-5425 2050);
PAINT WHITE (-5425 2050);
FORCENOTE
0X4D
(-5425 2125) 0;
DISPLAY LEFT (-5425 2125);
DISPLAY 0.638298 (-5425 2125);
PAINT WHITE (-5425 2125);
FORCENOTE
BOM NOTE
(1525 5000) 0;
DISPLAY LEFT (1525 5000);
DISPLAY 1.595745 (1525 5000);
PAINT WHITE (1525 5000);
FORCENOTE
MAIN SOURCE:RENESAS BOM
(1525 4875) 0;
DISPLAY LEFT (1525 4875);
DISPLAY 1.276596 (1525 4875);
PAINT WHITE (1525 4875);
FORCENOTE
PU25 = TBD/RAA229620GNP#HA0
(1525 4800) 0;
DISPLAY LEFT (1525 4800);
DISPLAY 1.021277 (1525 4800);
PAINT WHITE (1525 4800);
FORCENOTE
DIFFERENTIAL PAIR
(-4750 4350) 0;
DISPLAY LEFT (-4750 4350);
DISPLAY 0.808511 (-4750 4350);
PAINT WHITE (-4750 4350);
FORCENOTE
TRACE WIDTH = 10MIL
(-4750 4275) 0;
DISPLAY LEFT (-4750 4275);
DISPLAY 0.808511 (-4750 4275);
PAINT WHITE (-4750 4275);
FORCENOTE
PC253,PC250 = CH11006JB00
(1525 4050) 0;
DISPLAY LEFT (1525 4050);
DISPLAY 1.021277 (1525 4050);
PAINT WHITE (1525 4050);
FORCENOTE
PC244,PC245 = CH12206KB14
(1525 3975) 0;
DISPLAY LEFT (1525 3975);
DISPLAY 1.021277 (1525 3975);
PAINT WHITE (1525 3975);
FORCENOTE
PU25 = TBD/MP2857GQKT-001C-Z
(1525 3675) 0;
DISPLAY LEFT (1525 3675);
DISPLAY 1.021277 (1525 3675);
PAINT WHITE (1525 3675);
FORCENOTE
PC244,PC245,PR157,PC243 = EMPTY
(1525 3600) 0;
DISPLAY LEFT (1525 3600);
DISPLAY 1.021277 (1525 3600);
PAINT WHITE (1525 3600);
FORCENOTE
PR530,PR436,PR437=EMPTY
(1525 3450) 0;
DISPLAY LEFT (1525 3450);
DISPLAY 1.021277 (1525 3450);
PAINT WHITE (1525 3450);
FORCENOTE
PR159 = CS35232FB02
(1525 3375) 0;
DISPLAY LEFT (1525 3375);
DISPLAY 1.021277 (1525 3375);
PAINT WHITE (1525 3375);
FORCENOTE
PR181 = CS37502FB05
(1525 3300) 0;
DISPLAY LEFT (1525 3300);
DISPLAY 1.021277 (1525 3300);
PAINT WHITE (1525 3300);
FORCENOTE
PR602 = CS24992FB07
(1525 3225) 0;
DISPLAY LEFT (1525 3225);
DISPLAY 1.021277 (1525 3225);
PAINT WHITE (1525 3225);
FORCENOTE
PC250,PC253 = CH31004KB17
(1525 3150) 0;
DISPLAY LEFT (1525 3150);
DISPLAY 1.021277 (1525 3150);
PAINT WHITE (1525 3150);
FORCENOTE
PC251=CH5103KEB01
(1525 3000) 0;
DISPLAY LEFT (1525 3000);
DISPLAY 1.021277 (1525 3000);
PAINT WHITE (1525 3000);
FORCENOTE
PR4 = CS00002JB13
(1525 3525) 0;
DISPLAY LEFT (1525 3525);
DISPLAY 1.021277 (1525 3525);
PAINT WHITE (1525 3525);
FORCENOTE
PC6 = CH21006JB10
(1525 3075) 0;
DISPLAY LEFT (1525 3075);
DISPLAY 1.021277 (1525 3075);
PAINT WHITE (1525 3075);
FORCENOTE
3RD SOURCE:MPS BOM
(1525 3750) 0;
DISPLAY LEFT (1525 3750);
DISPLAY 1.276596 (1525 3750);
PAINT WHITE (1525 3750);
FORCENOTE
PR173,PR174 = CS01002FB07
(1525 4275) 0;
DISPLAY LEFT (1525 4275);
DISPLAY 1.021277 (1525 4275);
PAINT WHITE (1525 4275);
FORCENOTE
PC251 = CH5103KEB01
(1525 4125) 0;
DISPLAY LEFT (1525 4125);
DISPLAY 1.021277 (1525 4125);
PAINT WHITE (1525 4125);
FORCENOTE
PC243 = CH3104J1B00
(1525 3900) 0;
DISPLAY LEFT (1525 3900);
DISPLAY 1.021277 (1525 3900);
PAINT WHITE (1525 3900);
FORCENOTE
/1.47K
(-5075 2125) 0;
DISPLAY LEFT (-5075 2125);
DISPLAY 0.638298 (-5075 2125);
PAINT WHITE (-5075 2125);
FORCENOTE
0/5.23K
(-5075 2200) 0;
DISPLAY LEFT (-5075 2200);
DISPLAY 0.638298 (-5075 2200);
PAINT WHITE (-5075 2200);
FORCENOTE
TRACE SPACING = 5MIL
(-4750 4200) 0;
DISPLAY LEFT (-4750 4200);
DISPLAY 0.808511 (-4750 4200);
PAINT WHITE (-4750 4200);
FORCENOTE
MPS
(-5875 2050) 0;
DISPLAY LEFT (-5875 2050);
DISPLAY 0.638298 (-5875 2050);
PAINT WHITE (-5875 2050);
FORCENOTE
VR
(-5875 2300) 0;
DISPLAY LEFT (-5875 2300);
DISPLAY 0.808511 (-5875 2300);
PAINT WHITE (-5875 2300);
FORCENOTE
TRACE SPACING = 5MIL
(-4775 5300) 0;
DISPLAY LEFT (-4775 5300);
DISPLAY 0.808511 (-4775 5300);
PAINT WHITE (-4775 5300);
FORCENOTE
DC=+/-20MV
(1575 6625) 0;
DISPLAY LEFT (1575 6625);
DISPLAY 0.936170 (1575 6625);
PAINT WHITE (1575 6625);
FORCENOTE
EDC=130A
(1575 6325) 0;
DISPLAY LEFT (1575 6325);
DISPLAY 0.936170 (1575 6325);
PAINT WHITE (1575 6325);
FORCENOTE
TDC=105A
(1575 6400) 0;
DISPLAY LEFT (1575 6400);
DISPLAY 0.936170 (1575 6400);
PAINT WHITE (1575 6400);
FORCENOTE
MAX AC=VID+150MV
(1575 6550) 0;
DISPLAY LEFT (1575 6550);
DISPLAY 0.936170 (1575 6550);
PAINT WHITE (1575 6550);
FORCENOTE
MIN AC=VID-150MV
(1575 6475) 0;
DISPLAY LEFT (1575 6475);
DISPLAY 0.936170 (1575 6475);
PAINT WHITE (1575 6475);
FORCENOTE
MIN AC=VID-EDC*LL-110MV
(1575 7825) 0;
DISPLAY LEFT (1575 7825);
DISPLAY 0.936170 (1575 7825);
PAINT WHITE (1575 7825);
FORCENOTE
MAX AC=VID+200MV
(1575 7900) 0;
DISPLAY LEFT (1575 7900);
DISPLAY 0.936170 (1575 7900);
PAINT WHITE (1575 7900);
FORCENOTE
DEFAULT POWER-ON VID=0.9V
(1575 8125) 0;
DISPLAY LEFT (1575 8125);
DISPLAY 0.936170 (1575 8125);
PAINT WHITE (1575 8125);
FORCENOTE
VID=0.55-1.5V
(1575 8050) 0;
DISPLAY LEFT (1575 8050);
DISPLAY 0.936170 (1575 8050);
PAINT WHITE (1575 8050);
FORCENOTE
DC=+/-20MV
(1575 7975) 0;
DISPLAY LEFT (1575 7975);
DISPLAY 0.936170 (1575 7975);
PAINT WHITE (1575 7975);
FORCENOTE
PVDDCR_CPU0_P1 SPECFICATION
(1575 8272) 0;
DISPLAY LEFT (1575 8272);
DISPLAY 1.170213 (1575 8272);
PAINT WHITE (1575 8272);
FORCENOTE
DIFFERENTIAL PAIR
(-4775 5450) 0;
DISPLAY LEFT (-4775 5450);
DISPLAY 0.808511 (-4775 5450);
PAINT WHITE (-4775 5450);
FORCENOTE
TRACE WIDTH = 10MIL
(-4775 5375) 0;
DISPLAY LEFT (-4775 5375);
DISPLAY 0.808511 (-4775 5375);
PAINT WHITE (-4775 5375);
FORCENOTE
MAX LOAD STEP=200A
(1575 7525) 0;
DISPLAY LEFT (1575 7525);
DISPLAY 0.936170 (1575 7525);
PAINT WHITE (1575 7525);
FORCENOTE
TDC=175A
(1575 7750) 0;
DISPLAY LEFT (1575 7750);
DISPLAY 0.936170 (1575 7750);
PAINT WHITE (1575 7750);
FORCENOTE
EDC=230A
(1575 7675) 0;
DISPLAY LEFT (1575 7675);
DISPLAY 0.936170 (1575 7675);
PAINT WHITE (1575 7675);
FORCENOTE
OCP=276A (EDC*1.2)
(1575 7600) 0;
DISPLAY LEFT (1575 7600);
DISPLAY 0.936170 (1575 7600);
PAINT WHITE (1575 7600);
FORCENOTE
/52.3K
(-5075 2050) 0;
DISPLAY LEFT (-5075 2050);
DISPLAY 0.638298 (-5075 2050);
PAINT WHITE (-5075 2050);
FORCENOTE
INFINEON
(-5875 2125) 0;
DISPLAY LEFT (-5875 2125);
DISPLAY 0.638298 (-5875 2125);
PAINT WHITE (-5875 2125);
FORCENOTE
RENESAS
(-5875 2200) 0;
DISPLAY LEFT (-5875 2200);
DISPLAY 0.638298 (-5875 2200);
PAINT WHITE (-5875 2200);
FORCENOTE
PU25 = TBD/XDPE192C3B
(1525 4575) 0;
DISPLAY LEFT (1525 4575);
DISPLAY 1.021277 (1525 4575);
PAINT WHITE (1525 4575);
FORCENOTE
PR157 = CS25362FB02
(1525 4500) 0;
DISPLAY LEFT (1525 4500);
DISPLAY 1.021277 (1525 4500);
PAINT WHITE (1525 4500);
FORCENOTE
PR4 = CS21002FB06
(1525 4425) 0;
DISPLAY LEFT (1525 4425);
DISPLAY 1.021277 (1525 4425);
PAINT WHITE (1525 4425);
FORCENOTE
PR530,PR436,PR437 = EMPTY
(1525 4350) 0;
DISPLAY LEFT (1525 4350);
DISPLAY 1.021277 (1525 4350);
PAINT WHITE (1525 4350);
FORCENOTE
PR159 = CS21472FB02
(1525 4200) 0;
DISPLAY LEFT (1525 4200);
DISPLAY 1.021277 (1525 4200);
PAINT WHITE (1525 4200);
FORCENOTE
2ND SOURCE:INFENEON BOM
(1525 4650) 0;
DISPLAY LEFT (1525 4650);
DISPLAY 1.276596 (1525 4650);
PAINT WHITE (1525 4650);
FORCENOTE
LOAD-LINE=0.4MOHM
(1575 7375) 0;
DISPLAY LEFT (1575 7375);
DISPLAY 0.936170 (1575 7375);
PAINT WHITE (1575 7375);
FORCENOTE
MAX LOAD RELEASE=200A
(1575 7450) 0;
DISPLAY LEFT (1575 7450);
DISPLAY 0.936170 (1575 7450);
PAINT WHITE (1575 7450);
FORCENOTE
VID=0.75-1.2V
(1575 6700) 0;
DISPLAY LEFT (1575 6700);
DISPLAY 0.936170 (1575 6700);
PAINT WHITE (1575 6700);
FORCENOTE
WORK FREQUENCY=600KHZ
(1575 7300) 0;
DISPLAY LEFT (1575 7300);
DISPLAY 0.936170 (1575 7300);
PAINT WHITE (1575 7300);
FORCENOTE
EFFICIENCY > 90% @TDC
(1575 7225) 0;
DISPLAY LEFT (1575 7225);
DISPLAY 0.936170 (1575 7225);
PAINT WHITE (1575 7225);
FORCENOTE
SVI3 ADDRESS=PORT0 (0X1)
(1575 7150) 0;
DISPLAY LEFT (1575 7150);
DISPLAY 0.936170 (1575 7150);
PAINT WHITE (1575 7150);
FORCENOTE
IRM REV1.09
(1575 7075) 0;
DISPLAY LEFT (1575 7075);
DISPLAY 0.936170 (1575 7075);
PAINT WHITE (1575 7075);
FORCENOTE
DEFAULT POWER-ON VID=0.9V
(1575 6775) 0;
DISPLAY LEFT (1575 6775);
DISPLAY 0.936170 (1575 6775);
PAINT WHITE (1575 6775);
FORCENOTE
PVDDCR_SOC_P1 SPECFICATION
(1575 6900) 0;
DISPLAY LEFT (1575 6900);
DISPLAY 1.276596 (1575 6900);
PAINT WHITE (1575 6900);
FORCENOTE
OCP=156A (EDC*1.2)
(1575 6250) 0;
DISPLAY LEFT (1575 6250);
DISPLAY 0.936170 (1575 6250);
PAINT WHITE (1575 6250);
FORCENOTE
MAX LOAD STEP=45A
(1575 6175) 0;
DISPLAY LEFT (1575 6175);
DISPLAY 0.936170 (1575 6175);
PAINT WHITE (1575 6175);
FORCENOTE
MAX LOAD RELEASE=95A
(1575 6100) 0;
DISPLAY LEFT (1575 6100);
DISPLAY 0.936170 (1575 6100);
PAINT WHITE (1575 6100);
FORCENOTE
WORK FREQUENCY=600KHZ
(1575 6025) 0;
DISPLAY LEFT (1575 6025);
DISPLAY 0.936170 (1575 6025);
PAINT WHITE (1575 6025);
FORCENOTE
EFFICIENCY > 90% @TDC
(1575 5950) 0;
DISPLAY LEFT (1575 5950);
DISPLAY 0.936170 (1575 5950);
PAINT WHITE (1575 5950);
FORCENOTE
SVI3 ADDRESS=PORT0 (0X2)
(1575 5875) 0;
DISPLAY LEFT (1575 5875);
DISPLAY 0.936170 (1575 5875);
PAINT WHITE (1575 5875);
FORCENOTE
IRM REV1.09
(1575 5800) 0;
DISPLAY LEFT (1575 5800);
DISPLAY 0.936170 (1575 5800);
PAINT WHITE (1575 5800);
QUIT
